FILE_TYPE = MACRO_DRAWING;
SET COLOR_WIRE YELLOW;
SET COLOR_PROP MONO;
SET COLOR_DOT WHITE;
SET COLOR_ARC YELLOW;
SET COLOR_BODY GREEN;
SET COLOR_NOTE MONO;
SET PROP_DISPLAY VALUE;
SET PAGE_NUMBER P55;
FORCEADD OFFPAGE..1
R 2
(12525 4100);
FORCEPROP 2 LAST $XR0 96 
J 0
(12711 4100);
DISPLAY 0.638298 (12711 4100);
PAINT MONO (12711 4100);
FORCEPROP 2 LAST CDS_LIB mstr_standard
J 2
(12525 4100);
PAINT MONO (12525 4100);
DISPLAY INVISIBLE (12525 4100);
FORCEPROP 1 LAST OFFPAGE TRUE
J 2
(12200 3975);
DISPLAY 0.872340 (12200 3975);
PAINT GREEN (12200 3975);
DISPLAY INVISIBLE (12200 3975);
FORCEPROP 1 LAST COMMENT_BODY TRUE
J 2
(12400 4000);
DISPLAY 0.872340 (12400 4000);
PAINT GREEN (12400 4000);
DISPLAY INVISIBLE (12400 4000);
FORCEPROP 2 LAST PATH I10
J 2
(12225 4150);
DISPLAY 1.021277 (12225 4150);
PAINT ORANGE (12225 4150);
DISPLAY INVISIBLE (12225 4150);
FORCEADD OFFPAGE..1
(7975 1000);
FORCEPROP 2 LAST $XR0 112 
J 0
(7723 1000);
DISPLAY 0.638298 (7723 1000);
PAINT MONO (7723 1000);
FORCEPROP 2 LAST CDS_LIB mstr_standard
J 0
(7975 1000);
PAINT MONO (7975 1000);
DISPLAY INVISIBLE (7975 1000);
FORCEPROP 1 LAST OFFPAGE TRUE
J 0
(8300 875);
DISPLAY 1.170213 (8300 875);
PAINT GREEN (8300 875);
DISPLAY INVISIBLE (8300 875);
FORCEPROP 1 LAST COMMENT_BODY TRUE
J 0
(8100 900);
DISPLAY 1.170213 (8100 900);
PAINT GREEN (8100 900);
DISPLAY INVISIBLE (8100 900);
FORCEPROP 2 LAST PATH I100
J 0
(8025 1075);
DISPLAY 1.021277 (8025 1075);
PAINT ORANGE (8025 1075);
DISPLAY INVISIBLE (8025 1075);
FORCEADD OFFPAGE..1
(7975 950);
FORCEPROP 2 LAST $XR0 111 
J 0
(7723 950);
DISPLAY 0.638298 (7723 950);
PAINT MONO (7723 950);
FORCEPROP 2 LAST $XR1 21 
J 0
(7633 950);
DISPLAY 0.638298 (7633 950);
PAINT MONO (7633 950);
FORCEPROP 2 LAST $XR2 112 
J 0
(7513 950);
DISPLAY 0.638298 (7513 950);
PAINT MONO (7513 950);
FORCEPROP 2 LAST CDS_LIB mstr_standard
J 0
(7975 950);
PAINT MONO (7975 950);
DISPLAY INVISIBLE (7975 950);
FORCEPROP 1 LAST OFFPAGE TRUE
J 0
(8300 825);
DISPLAY 1.170213 (8300 825);
PAINT GREEN (8300 825);
DISPLAY INVISIBLE (8300 825);
FORCEPROP 1 LAST COMMENT_BODY TRUE
J 0
(8100 850);
DISPLAY 1.170213 (8100 850);
PAINT GREEN (8100 850);
DISPLAY INVISIBLE (8100 850);
FORCEPROP 2 LAST PATH I101
J 0
(8025 1025);
DISPLAY 1.021277 (8025 1025);
PAINT ORANGE (8025 1025);
DISPLAY INVISIBLE (8025 1025);
FORCEADD OFFPAGE..1
(7975 900);
FORCEPROP 2 LAST $XR0 112 
J 0
(7723 900);
DISPLAY 0.638298 (7723 900);
PAINT MONO (7723 900);
FORCEPROP 2 LAST $XR1 21 
J 0
(7633 900);
DISPLAY 0.638298 (7633 900);
PAINT MONO (7633 900);
FORCEPROP 2 LAST CDS_LIB mstr_standard
J 0
(7975 900);
PAINT MONO (7975 900);
DISPLAY INVISIBLE (7975 900);
FORCEPROP 1 LAST OFFPAGE TRUE
J 0
(8300 775);
DISPLAY 1.170213 (8300 775);
PAINT GREEN (8300 775);
DISPLAY INVISIBLE (8300 775);
FORCEPROP 1 LAST COMMENT_BODY TRUE
J 0
(8100 800);
DISPLAY 1.170213 (8100 800);
PAINT GREEN (8100 800);
DISPLAY INVISIBLE (8100 800);
FORCEPROP 2 LAST PATH I102
J 0
(8025 975);
DISPLAY 1.021277 (8025 975);
PAINT ORANGE (8025 975);
DISPLAY INVISIBLE (8025 975);
FORCEADD OFFPAGE..1
(7975 850);
FORCEPROP 2 LAST $XR0 112 
J 0
(7723 850);
DISPLAY 0.638298 (7723 850);
PAINT MONO (7723 850);
FORCEPROP 2 LAST $XR1 21 
J 0
(7633 850);
DISPLAY 0.638298 (7633 850);
PAINT MONO (7633 850);
FORCEPROP 2 LAST CDS_LIB mstr_standard
J 0
(7975 850);
PAINT MONO (7975 850);
DISPLAY INVISIBLE (7975 850);
FORCEPROP 1 LAST OFFPAGE TRUE
J 0
(8300 725);
DISPLAY 1.170213 (8300 725);
PAINT GREEN (8300 725);
DISPLAY INVISIBLE (8300 725);
FORCEPROP 1 LAST COMMENT_BODY TRUE
J 0
(8100 750);
DISPLAY 1.170213 (8100 750);
PAINT GREEN (8100 750);
DISPLAY INVISIBLE (8100 750);
FORCEPROP 2 LAST PATH I103
J 0
(8025 925);
DISPLAY 1.021277 (8025 925);
PAINT ORANGE (8025 925);
DISPLAY INVISIBLE (8025 925);
FORCEADD OFFPAGE..1
(7975 3800);
FORCEPROP 2 LAST $XR0 103 
J 0
(7723 3800);
DISPLAY 0.638298 (7723 3800);
PAINT MONO (7723 3800);
FORCEPROP 2 LAST CDS_LIB mstr_standard
J 0
(7975 3800);
PAINT MONO (7975 3800);
DISPLAY INVISIBLE (7975 3800);
FORCEPROP 1 LAST OFFPAGE TRUE
J 0
(8300 3675);
DISPLAY 1.170213 (8300 3675);
PAINT GREEN (8300 3675);
DISPLAY INVISIBLE (8300 3675);
FORCEPROP 1 LAST COMMENT_BODY TRUE
J 0
(8100 3700);
DISPLAY 1.170213 (8100 3700);
PAINT GREEN (8100 3700);
DISPLAY INVISIBLE (8100 3700);
FORCEPROP 2 LAST PATH I108
J 0
(8025 3875);
DISPLAY 1.021277 (8025 3875);
PAINT ORANGE (8025 3875);
DISPLAY INVISIBLE (8025 3875);
FORCEADD OFFPAGE..1
(7975 3850);
FORCEPROP 2 LAST $XR0 103 
J 0
(7723 3850);
DISPLAY 0.638298 (7723 3850);
PAINT MONO (7723 3850);
FORCEPROP 2 LAST CDS_LIB mstr_standard
J 0
(7975 3850);
PAINT MONO (7975 3850);
DISPLAY INVISIBLE (7975 3850);
FORCEPROP 1 LAST OFFPAGE TRUE
J 0
(8300 3725);
DISPLAY 1.170213 (8300 3725);
PAINT GREEN (8300 3725);
DISPLAY INVISIBLE (8300 3725);
FORCEPROP 1 LAST COMMENT_BODY TRUE
J 0
(8100 3750);
DISPLAY 1.170213 (8100 3750);
PAINT GREEN (8100 3750);
DISPLAY INVISIBLE (8100 3750);
FORCEPROP 2 LAST PATH I109
J 0
(8025 3925);
DISPLAY 1.021277 (8025 3925);
PAINT ORANGE (8025 3925);
DISPLAY INVISIBLE (8025 3925);
FORCEADD RES..2
R 2
(6575 2650);
FORCEPROP 1 LAST LOCATION R7P19
J 2
(6530 2775);
DISPLAY 0.617021 (6530 2775);
PAINT AQUA (6530 2775);
FORCEPROP 1 LAST PART_NUMBER G21796-017
J 2
(6535 2525);
DISPLAY 0.617021 (6535 2525);
PAINT BLUE (6535 2525);
FORCEPROP 1 LAST VALUE 100.0
J 2
(6530 2725);
DISPLAY 0.617021 (6530 2725);
PAINT SKYBLUE (6530 2725);
FORCEPROP 1 LAST TOLERANCE 1%
J 2
(6530 2675);
DISPLAY 0.617021 (6530 2675);
PAINT SKYBLUE (6530 2675);
FORCEPROP 1 LAST PACK_TYPE 0402
J 2
(6535 2475);
DISPLAY 0.617021 (6535 2475);
PAINT SKYBLUE (6535 2475);
FORCEPROP 1 LAST MATERIAL CHIP
J 2
(6535 2575);
DISPLAY 0.617021 (6535 2575);
PAINT SKYBLUE (6535 2575);
FORCEPROP 1 LAST WATTAGE 1/16W
J 2
(6535 2625);
DISPLAY 0.617021 (6535 2625);
PAINT SKYBLUE (6535 2625);
FORCEPROP 1 LASTPIN (6575 2550) $PN 2
J 2
(6570 2560);
DISPLAY 0.617021 (6570 2560);
PAINT ORANGE (6570 2560);
FORCEPROP 1 LASTPIN (6575 2750) $PN 1
J 2
(6570 2712);
DISPLAY 0.617021 (6570 2712);
PAINT ORANGE (6570 2712);
FORCEPROP 2 LAST SEC_TYPE 0402
J 0
(6525 2875);
DISPLAY 1.021277 (6525 2875);
PAINT ORANGE (6525 2875);
DISPLAY INVISIBLE (6525 2875);
FORCEPROP 2 LAST CDS_LIB mstr_discrete
J 0
(6575 2650);
PAINT ORANGE (6575 2650);
DISPLAY INVISIBLE (6575 2650);
FORCEPROP 2 LAST BOM_COST PROC_SOCKET
J 0
(6550 2875);
PAINT MONO (6550 2875);
DISPLAY INVISIBLE (6550 2875);
FORCEPROP 2 LAST SEC 1
J 0
(6525 2875);
DISPLAY 0.680851 (6525 2875);
PAINT MONO (6525 2875);
DISPLAY INVISIBLE (6525 2875);
FORCEPROP 2 LAST CDS_LOCATION R7P19
J 2
(6530 2775);
DISPLAY 0.617021 (6530 2775);
PAINT AQUA (6530 2775);
DISPLAY INVISIBLE (6530 2775);
FORCEPROP 1 LAST PATH I115
J 2
(6525 2825);
DISPLAY 0.978723 (6525 2825);
PAINT WHITE (6525 2825);
DISPLAY INVISIBLE (6525 2825);
FORCEPROP 2 LAST ROOM CPU1
J 0
(6550 2825);
PAINT MONO (6550 2825);
DISPLAY INVISIBLE (6550 2825);
FORCEADD RES..2
R 2
(7700 2525);
FORCEPROP 1 LAST LOCATION R3D1
J 2
(7655 2650);
DISPLAY 0.617021 (7655 2650);
PAINT AQUA (7655 2650);
FORCEPROP 1 LAST PART_NUMBER G21796-365
J 2
(7660 2400);
DISPLAY 0.617021 (7660 2400);
PAINT BLUE (7660 2400);
FORCEPROP 1 LAST VALUE 90.9
J 2
(7655 2600);
DISPLAY 0.617021 (7655 2600);
PAINT SKYBLUE (7655 2600);
FORCEPROP 1 LAST TOLERANCE 1%
J 2
(7655 2550);
DISPLAY 0.617021 (7655 2550);
PAINT SKYBLUE (7655 2550);
FORCEPROP 1 LAST PACK_TYPE 0402
J 2
(7660 2350);
DISPLAY 0.617021 (7660 2350);
PAINT SKYBLUE (7660 2350);
FORCEPROP 1 LAST MATERIAL CHIP
J 2
(7660 2450);
DISPLAY 0.617021 (7660 2450);
PAINT SKYBLUE (7660 2450);
FORCEPROP 1 LAST WATTAGE 1/16W
J 2
(7660 2500);
DISPLAY 0.617021 (7660 2500);
PAINT SKYBLUE (7660 2500);
FORCEPROP 1 LASTPIN (7700 2425) $PN 2
J 2
(7695 2435);
DISPLAY 0.617021 (7695 2435);
PAINT ORANGE (7695 2435);
FORCEPROP 1 LASTPIN (7700 2625) $PN 1
J 2
(7695 2587);
DISPLAY 0.617021 (7695 2587);
PAINT ORANGE (7695 2587);
FORCEPROP 2 LAST SEC_TYPE 0402
J 0
(7650 2750);
DISPLAY 1.021277 (7650 2750);
PAINT ORANGE (7650 2750);
DISPLAY INVISIBLE (7650 2750);
FORCEPROP 2 LAST CDS_LIB mstr_discrete
J 0
(7700 2525);
PAINT ORANGE (7700 2525);
DISPLAY INVISIBLE (7700 2525);
FORCEPROP 2 LAST BOM_COST PROC_SOCKET
J 0
(7675 2750);
PAINT MONO (7675 2750);
DISPLAY INVISIBLE (7675 2750);
FORCEPROP 2 LAST SEC 1
J 0
(7650 2750);
DISPLAY 0.680851 (7650 2750);
PAINT MONO (7650 2750);
DISPLAY INVISIBLE (7650 2750);
FORCEPROP 2 LAST CDS_LOCATION R3D1
J 2
(7655 2650);
DISPLAY 0.617021 (7655 2650);
PAINT AQUA (7655 2650);
DISPLAY INVISIBLE (7655 2650);
FORCEPROP 1 LAST PATH I116
J 2
(7650 2700);
DISPLAY 0.978723 (7650 2700);
PAINT WHITE (7650 2700);
DISPLAY INVISIBLE (7650 2700);
FORCEPROP 2 LAST ROOM CPU1
J 0
(7675 2700);
PAINT MONO (7675 2700);
DISPLAY INVISIBLE (7675 2700);
FORCEADD RES..2
R 2
(7475 2575);
FORCEPROP 1 LAST LOCATION R3D2
J 2
(7430 2700);
DISPLAY 0.617021 (7430 2700);
PAINT AQUA (7430 2700);
FORCEPROP 1 LAST PART_NUMBER G21796-365
J 2
(7435 2450);
DISPLAY 0.617021 (7435 2450);
PAINT BLUE (7435 2450);
FORCEPROP 1 LAST VALUE 90.9
J 2
(7430 2650);
DISPLAY 0.617021 (7430 2650);
PAINT SKYBLUE (7430 2650);
FORCEPROP 1 LAST TOLERANCE 1%
J 2
(7430 2600);
DISPLAY 0.617021 (7430 2600);
PAINT SKYBLUE (7430 2600);
FORCEPROP 1 LAST PACK_TYPE 0402
J 2
(7435 2400);
DISPLAY 0.617021 (7435 2400);
PAINT SKYBLUE (7435 2400);
FORCEPROP 1 LAST MATERIAL CHIP
J 2
(7435 2500);
DISPLAY 0.617021 (7435 2500);
PAINT SKYBLUE (7435 2500);
FORCEPROP 1 LAST WATTAGE 1/16W
J 2
(7435 2550);
DISPLAY 0.617021 (7435 2550);
PAINT SKYBLUE (7435 2550);
FORCEPROP 1 LASTPIN (7475 2475) $PN 2
J 2
(7470 2485);
DISPLAY 0.617021 (7470 2485);
PAINT ORANGE (7470 2485);
FORCEPROP 1 LASTPIN (7475 2675) $PN 1
J 2
(7470 2637);
DISPLAY 0.617021 (7470 2637);
PAINT ORANGE (7470 2637);
FORCEPROP 2 LAST SEC_TYPE 0402
J 0
(7425 2800);
DISPLAY 1.021277 (7425 2800);
PAINT ORANGE (7425 2800);
DISPLAY INVISIBLE (7425 2800);
FORCEPROP 2 LAST CDS_LIB mstr_discrete
J 0
(7475 2575);
PAINT ORANGE (7475 2575);
DISPLAY INVISIBLE (7475 2575);
FORCEPROP 2 LAST BOM_COST PROC_SOCKET
J 0
(7450 2800);
PAINT MONO (7450 2800);
DISPLAY INVISIBLE (7450 2800);
FORCEPROP 2 LAST SEC 1
J 0
(7425 2800);
DISPLAY 0.680851 (7425 2800);
PAINT MONO (7425 2800);
DISPLAY INVISIBLE (7425 2800);
FORCEPROP 2 LAST CDS_LOCATION R3D2
J 2
(7430 2700);
DISPLAY 0.617021 (7430 2700);
PAINT AQUA (7430 2700);
DISPLAY INVISIBLE (7430 2700);
FORCEPROP 1 LAST PATH I117
J 2
(7425 2750);
DISPLAY 0.978723 (7425 2750);
PAINT WHITE (7425 2750);
DISPLAY INVISIBLE (7425 2750);
FORCEPROP 2 LAST ROOM CPU1
J 0
(7450 2750);
PAINT MONO (7450 2750);
DISPLAY INVISIBLE (7450 2750);
FORCEADD RES..2
R 2
(7250 2575);
FORCEPROP 1 LAST LOCATION R3D3
J 2
(7205 2700);
DISPLAY 0.617021 (7205 2700);
PAINT AQUA (7205 2700);
FORCEPROP 1 LAST PART_NUMBER G21796-017
J 2
(7210 2450);
DISPLAY 0.617021 (7210 2450);
PAINT BLUE (7210 2450);
FORCEPROP 1 LAST VALUE 100.0
J 2
(7205 2650);
DISPLAY 0.617021 (7205 2650);
PAINT SKYBLUE (7205 2650);
FORCEPROP 1 LAST TOLERANCE 1%
J 2
(7205 2600);
DISPLAY 0.617021 (7205 2600);
PAINT SKYBLUE (7205 2600);
FORCEPROP 1 LAST PACK_TYPE 0402
J 2
(7210 2400);
DISPLAY 0.617021 (7210 2400);
PAINT SKYBLUE (7210 2400);
FORCEPROP 1 LAST MATERIAL CHIP
J 2
(7210 2500);
DISPLAY 0.617021 (7210 2500);
PAINT SKYBLUE (7210 2500);
FORCEPROP 1 LAST WATTAGE 1/16W
J 2
(7210 2550);
DISPLAY 0.617021 (7210 2550);
PAINT SKYBLUE (7210 2550);
FORCEPROP 1 LASTPIN (7250 2475) $PN 2
J 2
(7245 2485);
DISPLAY 0.617021 (7245 2485);
PAINT ORANGE (7245 2485);
FORCEPROP 1 LASTPIN (7250 2675) $PN 1
J 2
(7245 2637);
DISPLAY 0.617021 (7245 2637);
PAINT ORANGE (7245 2637);
FORCEPROP 2 LAST SEC_TYPE 0402
J 0
(7200 2800);
DISPLAY 1.021277 (7200 2800);
PAINT ORANGE (7200 2800);
DISPLAY INVISIBLE (7200 2800);
FORCEPROP 2 LAST CDS_LIB mstr_discrete
J 0
(7250 2575);
PAINT ORANGE (7250 2575);
DISPLAY INVISIBLE (7250 2575);
FORCEPROP 2 LAST BOM_COST PROC_SOCKET
J 0
(7225 2800);
PAINT MONO (7225 2800);
DISPLAY INVISIBLE (7225 2800);
FORCEPROP 2 LAST SEC 1
J 0
(7200 2800);
DISPLAY 0.680851 (7200 2800);
PAINT MONO (7200 2800);
DISPLAY INVISIBLE (7200 2800);
FORCEPROP 2 LAST CDS_LOCATION R3D3
J 2
(7205 2700);
DISPLAY 0.617021 (7205 2700);
PAINT AQUA (7205 2700);
DISPLAY INVISIBLE (7205 2700);
FORCEPROP 1 LAST PATH I118
J 2
(7200 2750);
DISPLAY 0.978723 (7200 2750);
PAINT WHITE (7200 2750);
DISPLAY INVISIBLE (7200 2750);
FORCEPROP 2 LAST ROOM CPU1
J 0
(7225 2750);
PAINT MONO (7225 2750);
DISPLAY INVISIBLE (7225 2750);
FORCEADD RES..2
R 2
(7025 2575);
FORCEPROP 1 LAST LOCATION R7P16
J 2
(6980 2700);
DISPLAY 0.617021 (6980 2700);
PAINT AQUA (6980 2700);
FORCEPROP 1 LAST PART_NUMBER G21796-365
J 2
(6985 2450);
DISPLAY 0.617021 (6985 2450);
PAINT BLUE (6985 2450);
FORCEPROP 1 LAST VALUE 90.9
J 2
(6980 2650);
DISPLAY 0.617021 (6980 2650);
PAINT SKYBLUE (6980 2650);
FORCEPROP 1 LAST TOLERANCE 1%
J 2
(6980 2600);
DISPLAY 0.617021 (6980 2600);
PAINT SKYBLUE (6980 2600);
FORCEPROP 1 LAST PACK_TYPE 0402
J 2
(6985 2400);
DISPLAY 0.617021 (6985 2400);
PAINT SKYBLUE (6985 2400);
FORCEPROP 1 LAST MATERIAL CHIP
J 2
(6985 2500);
DISPLAY 0.617021 (6985 2500);
PAINT SKYBLUE (6985 2500);
FORCEPROP 1 LAST WATTAGE 1/16W
J 2
(6985 2550);
DISPLAY 0.617021 (6985 2550);
PAINT SKYBLUE (6985 2550);
FORCEPROP 1 LASTPIN (7025 2475) $PN 2
J 2
(7020 2485);
DISPLAY 0.617021 (7020 2485);
PAINT ORANGE (7020 2485);
FORCEPROP 1 LASTPIN (7025 2675) $PN 1
J 2
(7020 2637);
DISPLAY 0.617021 (7020 2637);
PAINT ORANGE (7020 2637);
FORCEPROP 2 LAST SEC_TYPE 0402
J 0
(6975 2800);
DISPLAY 1.021277 (6975 2800);
PAINT ORANGE (6975 2800);
DISPLAY INVISIBLE (6975 2800);
FORCEPROP 2 LAST CDS_LIB mstr_discrete
J 0
(7025 2575);
PAINT ORANGE (7025 2575);
DISPLAY INVISIBLE (7025 2575);
FORCEPROP 2 LAST BOM_COST PROC_SOCKET
J 0
(7000 2800);
PAINT MONO (7000 2800);
DISPLAY INVISIBLE (7000 2800);
FORCEPROP 2 LAST SEC 1
J 0
(6975 2800);
DISPLAY 0.680851 (6975 2800);
PAINT MONO (6975 2800);
DISPLAY INVISIBLE (6975 2800);
FORCEPROP 2 LAST CDS_LOCATION R7P16
J 2
(6980 2700);
DISPLAY 0.617021 (6980 2700);
PAINT AQUA (6980 2700);
DISPLAY INVISIBLE (6980 2700);
FORCEPROP 1 LAST PATH I119
J 2
(6975 2750);
DISPLAY 0.978723 (6975 2750);
PAINT WHITE (6975 2750);
DISPLAY INVISIBLE (6975 2750);
FORCEPROP 2 LAST ROOM CPU1
J 0
(7000 2750);
PAINT MONO (7000 2750);
DISPLAY INVISIBLE (7000 2750);
FORCEADD GND..1
(6575 2225);
FORCEPROP 3 LASTPIN (6575 2275) SIG_NAME GND\g
J 0
(6585 2285);
DISPLAY 0.659574 (6585 2285);
PAINT MONO (6585 2285);
DISPLAY INVISIBLE (6585 2285);
FORCEPROP 1 LAST VOLTAGE 0.0V
J 0
(6530 2182);
DISPLAY 0.340426 (6530 2182);
PAINT SKYBLUE (6530 2182);
DISPLAY INVISIBLE (6530 2182);
FORCEPROP 1 LAST SIZE 1B
J 0
(6650 2175);
DISPLAY 1.170213 (6650 2175);
PAINT GREEN (6650 2175);
DISPLAY INVISIBLE (6650 2175);
FORCEPROP 2 LAST CDS_LIB mstr_symbols
J 0
(6575 2225);
PAINT ORANGE (6575 2225);
DISPLAY INVISIBLE (6575 2225);
FORCEPROP 1 LAST BODY_TYPE PLUMBING
J 0
(6530 2182);
DISPLAY 0.340426 (6530 2182);
PAINT GREEN (6530 2182);
DISPLAY INVISIBLE (6530 2182);
FORCEPROP 1 LAST PATH I121
J 0
(6650 2225);
DISPLAY 0.872340 (6650 2225);
PAINT AQUA (6650 2225);
DISPLAY INVISIBLE (6650 2225);
FORCEPROP 1 LAST HDL_POWER GND
J 0
(6575 2375);
DISPLAY 1.170213 (6575 2375);
PAINT GREEN (6575 2375);
DISPLAY INVISIBLE (6575 2375);
FORCEADD GND..1
(6575 1025);
FORCEPROP 3 LASTPIN (6575 1075) SIG_NAME GND\g
J 0
(6585 1085);
DISPLAY 0.659574 (6585 1085);
PAINT MONO (6585 1085);
DISPLAY INVISIBLE (6585 1085);
FORCEPROP 1 LAST VOLTAGE 0.0V
J 0
(6530 982);
DISPLAY 0.340426 (6530 982);
PAINT SKYBLUE (6530 982);
DISPLAY INVISIBLE (6530 982);
FORCEPROP 2 LAST CDS_LIB mstr_symbols
J 0
(6575 1025);
PAINT ORANGE (6575 1025);
DISPLAY INVISIBLE (6575 1025);
FORCEPROP 1 LAST SIZE 1B
J 0
(6650 975);
DISPLAY 1.170213 (6650 975);
PAINT GREEN (6650 975);
DISPLAY INVISIBLE (6650 975);
FORCEPROP 1 LAST BODY_TYPE PLUMBING
J 0
(6530 982);
DISPLAY 0.340426 (6530 982);
PAINT GREEN (6530 982);
DISPLAY INVISIBLE (6530 982);
FORCEPROP 1 LAST PATH I122
J 0
(6650 1025);
DISPLAY 0.872340 (6650 1025);
PAINT AQUA (6650 1025);
DISPLAY INVISIBLE (6650 1025);
FORCEPROP 1 LAST HDL_POWER GND
J 0
(6575 1175);
DISPLAY 1.170213 (6575 1175);
PAINT GREEN (6575 1175);
DISPLAY INVISIBLE (6575 1175);
FORCEADD RES..2
R 2
(6575 1425);
FORCEPROP 1 LAST LOCATION R7P8
J 2
(6530 1550);
DISPLAY 0.617021 (6530 1550);
PAINT AQUA (6530 1550);
FORCEPROP 1 LAST PART_NUMBER G21796-047
J 2
(6535 1300);
DISPLAY 0.617021 (6535 1300);
PAINT BLUE (6535 1300);
FORCEPROP 1 LAST VALUE 49.9
J 2
(6530 1500);
DISPLAY 0.617021 (6530 1500);
PAINT SKYBLUE (6530 1500);
FORCEPROP 1 LAST TOLERANCE 1%
J 2
(6530 1450);
DISPLAY 0.617021 (6530 1450);
PAINT SKYBLUE (6530 1450);
FORCEPROP 1 LAST PACK_TYPE 0402
J 2
(6535 1250);
DISPLAY 0.617021 (6535 1250);
PAINT SKYBLUE (6535 1250);
FORCEPROP 1 LAST MATERIAL CHIP
J 2
(6535 1350);
DISPLAY 0.617021 (6535 1350);
PAINT SKYBLUE (6535 1350);
FORCEPROP 1 LAST WATTAGE 1/16W
J 2
(6535 1400);
DISPLAY 0.617021 (6535 1400);
PAINT SKYBLUE (6535 1400);
FORCEPROP 1 LASTPIN (6575 1325) $PN 2
J 2
(6570 1335);
DISPLAY 0.617021 (6570 1335);
PAINT ORANGE (6570 1335);
FORCEPROP 1 LASTPIN (6575 1525) $PN 1
J 2
(6570 1487);
DISPLAY 0.617021 (6570 1487);
PAINT ORANGE (6570 1487);
FORCEPROP 2 LAST CDS_LIB mstr_discrete
J 0
(6575 1425);
PAINT ORANGE (6575 1425);
DISPLAY INVISIBLE (6575 1425);
FORCEPROP 2 LAST SEC_TYPE 0402
J 0
(6525 1650);
DISPLAY 1.021277 (6525 1650);
PAINT ORANGE (6525 1650);
DISPLAY INVISIBLE (6525 1650);
FORCEPROP 2 LAST BOM_COST PROC_SOCKET
J 0
(6550 1650);
PAINT MONO (6550 1650);
DISPLAY INVISIBLE (6550 1650);
FORCEPROP 2 LAST SEC 1
J 0
(6525 1650);
DISPLAY 0.680851 (6525 1650);
PAINT MONO (6525 1650);
DISPLAY INVISIBLE (6525 1650);
FORCEPROP 2 LAST CDS_LOCATION R7P8
J 2
(6530 1550);
DISPLAY 0.617021 (6530 1550);
PAINT AQUA (6530 1550);
DISPLAY INVISIBLE (6530 1550);
FORCEPROP 1 LAST PATH I123
J 2
(6525 1600);
DISPLAY 0.978723 (6525 1600);
PAINT WHITE (6525 1600);
DISPLAY INVISIBLE (6525 1600);
FORCEPROP 2 LAST ROOM CPU1
J 0
(6550 1600);
PAINT MONO (6550 1600);
DISPLAY INVISIBLE (6550 1600);
FORCEADD RES..2
R 2
(6775 1425);
FORCEPROP 1 LAST LOCATION R7P10
J 2
(6730 1550);
DISPLAY 0.617021 (6730 1550);
PAINT AQUA (6730 1550);
FORCEPROP 1 LAST PART_NUMBER G21796-047
J 2
(6735 1300);
DISPLAY 0.617021 (6735 1300);
PAINT BLUE (6735 1300);
FORCEPROP 1 LAST VALUE 49.9
J 2
(6730 1500);
DISPLAY 0.617021 (6730 1500);
PAINT SKYBLUE (6730 1500);
FORCEPROP 1 LAST TOLERANCE 1%
J 2
(6730 1450);
DISPLAY 0.617021 (6730 1450);
PAINT SKYBLUE (6730 1450);
FORCEPROP 1 LAST PACK_TYPE 0402
J 2
(6735 1250);
DISPLAY 0.617021 (6735 1250);
PAINT SKYBLUE (6735 1250);
FORCEPROP 1 LAST MATERIAL CHIP
J 2
(6735 1350);
DISPLAY 0.617021 (6735 1350);
PAINT SKYBLUE (6735 1350);
FORCEPROP 1 LAST WATTAGE 1/16W
J 2
(6735 1400);
DISPLAY 0.617021 (6735 1400);
PAINT SKYBLUE (6735 1400);
FORCEPROP 1 LASTPIN (6775 1325) $PN 2
J 2
(6770 1335);
DISPLAY 0.617021 (6770 1335);
PAINT ORANGE (6770 1335);
FORCEPROP 1 LASTPIN (6775 1525) $PN 1
J 2
(6770 1487);
DISPLAY 0.617021 (6770 1487);
PAINT ORANGE (6770 1487);
FORCEPROP 2 LAST SEC_TYPE 0402
J 0
(6725 1650);
DISPLAY 1.021277 (6725 1650);
PAINT ORANGE (6725 1650);
DISPLAY INVISIBLE (6725 1650);
FORCEPROP 2 LAST CDS_LIB mstr_discrete
J 0
(6775 1425);
PAINT ORANGE (6775 1425);
DISPLAY INVISIBLE (6775 1425);
FORCEPROP 2 LAST BOM_COST PROC_SOCKET
J 0
(6750 1650);
PAINT MONO (6750 1650);
DISPLAY INVISIBLE (6750 1650);
FORCEPROP 2 LAST SEC 1
J 0
(6725 1650);
DISPLAY 0.680851 (6725 1650);
PAINT MONO (6725 1650);
DISPLAY INVISIBLE (6725 1650);
FORCEPROP 2 LAST CDS_LOCATION R7P10
J 2
(6730 1550);
DISPLAY 0.617021 (6730 1550);
PAINT AQUA (6730 1550);
DISPLAY INVISIBLE (6730 1550);
FORCEPROP 1 LAST PATH I124
J 2
(6725 1600);
DISPLAY 0.978723 (6725 1600);
PAINT WHITE (6725 1600);
DISPLAY INVISIBLE (6725 1600);
FORCEPROP 2 LAST ROOM CPU1
J 0
(6750 1600);
PAINT MONO (6750 1600);
DISPLAY INVISIBLE (6750 1600);
FORCEADD RES..2
R 2
(7000 1425);
FORCEPROP 1 LAST LOCATION R3D19
J 2
(6955 1550);
DISPLAY 0.617021 (6955 1550);
PAINT AQUA (6955 1550);
FORCEPROP 1 LAST PART_NUMBER G21796-047
J 2
(6960 1300);
DISPLAY 0.617021 (6960 1300);
PAINT BLUE (6960 1300);
FORCEPROP 1 LAST VALUE 49.9
J 2
(6955 1500);
DISPLAY 0.617021 (6955 1500);
PAINT SKYBLUE (6955 1500);
FORCEPROP 1 LAST TOLERANCE 1%
J 2
(6955 1450);
DISPLAY 0.617021 (6955 1450);
PAINT SKYBLUE (6955 1450);
FORCEPROP 1 LAST PACK_TYPE 0402
J 2
(6960 1250);
DISPLAY 0.617021 (6960 1250);
PAINT SKYBLUE (6960 1250);
FORCEPROP 1 LAST MATERIAL CHIP
J 2
(6960 1350);
DISPLAY 0.617021 (6960 1350);
PAINT SKYBLUE (6960 1350);
FORCEPROP 1 LAST WATTAGE 1/16W
J 2
(6960 1400);
DISPLAY 0.617021 (6960 1400);
PAINT SKYBLUE (6960 1400);
FORCEPROP 1 LASTPIN (7000 1325) $PN 2
J 2
(6995 1335);
DISPLAY 0.617021 (6995 1335);
PAINT ORANGE (6995 1335);
FORCEPROP 1 LASTPIN (7000 1525) $PN 1
J 2
(6995 1487);
DISPLAY 0.617021 (6995 1487);
PAINT ORANGE (6995 1487);
FORCEPROP 2 LAST SEC_TYPE 0402
J 0
(6950 1650);
DISPLAY 1.021277 (6950 1650);
PAINT ORANGE (6950 1650);
DISPLAY INVISIBLE (6950 1650);
FORCEPROP 2 LAST CDS_LIB mstr_discrete
J 0
(7000 1425);
PAINT ORANGE (7000 1425);
DISPLAY INVISIBLE (7000 1425);
FORCEPROP 2 LAST BOM_COST PROC_SOCKET
J 0
(6975 1650);
PAINT MONO (6975 1650);
DISPLAY INVISIBLE (6975 1650);
FORCEPROP 2 LAST SEC 1
J 0
(6950 1650);
DISPLAY 0.680851 (6950 1650);
PAINT MONO (6950 1650);
DISPLAY INVISIBLE (6950 1650);
FORCEPROP 2 LAST CDS_LOCATION R3D19
J 2
(6955 1550);
DISPLAY 0.617021 (6955 1550);
PAINT AQUA (6955 1550);
DISPLAY INVISIBLE (6955 1550);
FORCEPROP 1 LAST PATH I125
J 2
(6950 1600);
DISPLAY 0.978723 (6950 1600);
PAINT WHITE (6950 1600);
DISPLAY INVISIBLE (6950 1600);
FORCEPROP 2 LAST ROOM CPU1
J 0
(6975 1600);
PAINT MONO (6975 1600);
DISPLAY INVISIBLE (6975 1600);
FORCEADD RES..2
R 2
(7200 1425);
FORCEPROP 1 LAST LOCATION R7P11
J 2
(7155 1550);
DISPLAY 0.617021 (7155 1550);
PAINT AQUA (7155 1550);
FORCEPROP 1 LAST PART_NUMBER G21796-047
J 2
(7235 1300);
DISPLAY 0.617021 (7235 1300);
PAINT BLUE (7235 1300);
FORCEPROP 1 LAST VALUE 49.9
J 2
(7155 1500);
DISPLAY 0.617021 (7155 1500);
PAINT SKYBLUE (7155 1500);
FORCEPROP 1 LAST TOLERANCE 1%
J 2
(7155 1450);
DISPLAY 0.617021 (7155 1450);
PAINT SKYBLUE (7155 1450);
FORCEPROP 1 LAST PACK_TYPE 0402
J 2
(7160 1250);
DISPLAY 0.617021 (7160 1250);
PAINT SKYBLUE (7160 1250);
FORCEPROP 1 LAST MATERIAL CHIP
J 2
(7160 1350);
DISPLAY 0.617021 (7160 1350);
PAINT SKYBLUE (7160 1350);
FORCEPROP 1 LAST WATTAGE 1/16W
J 2
(7160 1400);
DISPLAY 0.617021 (7160 1400);
PAINT SKYBLUE (7160 1400);
FORCEPROP 1 LASTPIN (7200 1325) $PN 2
J 2
(7195 1335);
DISPLAY 0.617021 (7195 1335);
PAINT ORANGE (7195 1335);
FORCEPROP 1 LASTPIN (7200 1525) $PN 1
J 2
(7195 1487);
DISPLAY 0.617021 (7195 1487);
PAINT ORANGE (7195 1487);
FORCEPROP 2 LAST SEC_TYPE 0402
J 0
(7150 1650);
DISPLAY 1.021277 (7150 1650);
PAINT ORANGE (7150 1650);
DISPLAY INVISIBLE (7150 1650);
FORCEPROP 2 LAST CDS_LIB mstr_discrete
J 0
(7200 1425);
PAINT ORANGE (7200 1425);
DISPLAY INVISIBLE (7200 1425);
FORCEPROP 2 LAST BOM_COST PROC_SOCKET
J 0
(7175 1650);
PAINT MONO (7175 1650);
DISPLAY INVISIBLE (7175 1650);
FORCEPROP 2 LAST SEC 1
J 0
(7150 1650);
DISPLAY 0.680851 (7150 1650);
PAINT MONO (7150 1650);
DISPLAY INVISIBLE (7150 1650);
FORCEPROP 2 LAST CDS_LOCATION R7P11
J 2
(7155 1550);
DISPLAY 0.617021 (7155 1550);
PAINT AQUA (7155 1550);
DISPLAY INVISIBLE (7155 1550);
FORCEPROP 1 LAST PATH I126
J 2
(7150 1600);
DISPLAY 0.978723 (7150 1600);
PAINT WHITE (7150 1600);
DISPLAY INVISIBLE (7150 1600);
FORCEPROP 2 LAST ROOM CPU1
J 0
(7175 1600);
PAINT MONO (7175 1600);
DISPLAY INVISIBLE (7175 1600);
FORCEADD OFFPAGE..3
(13725 3650);
FORCEPROP 2 LAST $XR0 193 
J 0
(13939 3650);
DISPLAY 0.638298 (13939 3650);
PAINT MONO (13939 3650);
FORCEPROP 2 LAST $XR1 223 
J 0
(14059 3650);
DISPLAY 0.638298 (14059 3650);
PAINT MONO (14059 3650);
FORCEPROP 2 LAST $XR2 226 
J 0
(14179 3650);
DISPLAY 0.638298 (14179 3650);
PAINT MONO (14179 3650);
FORCEPROP 2 LAST CDS_LIB mstr_standard
J 0
(13725 3650);
PAINT MONO (13725 3650);
DISPLAY INVISIBLE (13725 3650);
FORCEPROP 1 LAST OFFPAGE TRUE
J 0
(14050 3525);
DISPLAY 1.170213 (14050 3525);
PAINT GREEN (14050 3525);
DISPLAY INVISIBLE (14050 3525);
FORCEPROP 1 LAST COMMENT_BODY TRUE
J 0
(13675 3550);
DISPLAY 1.170213 (13675 3550);
PAINT GREEN (13675 3550);
DISPLAY INVISIBLE (13675 3550);
FORCEPROP 2 LAST PATH I13
J 0
(13925 3725);
DISPLAY 1.021277 (13925 3725);
PAINT ORANGE (13925 3725);
DISPLAY INVISIBLE (13925 3725);
FORCEADD OFFPAGE..4
(12525 3900);
FORCEPROP 2 LAST $XR0 118 
J 0
(12711 3900);
DISPLAY 0.638298 (12711 3900);
PAINT MONO (12711 3900);
FORCEPROP 2 LAST $XR1 21 
J 0
(12831 3900);
DISPLAY 0.638298 (12831 3900);
PAINT MONO (12831 3900);
FORCEPROP 2 LAST CDS_LIB mstr_standard
J 0
(12525 3900);
PAINT ORANGE (12525 3900);
DISPLAY INVISIBLE (12525 3900);
FORCEPROP 1 LAST OFFPAGE TRUE
J 0
(12850 3775);
DISPLAY 1.170213 (12850 3775);
PAINT GREEN (12850 3775);
DISPLAY INVISIBLE (12850 3775);
FORCEPROP 1 LAST COMMENT_BODY TRUE
J 0
(12500 3800);
DISPLAY 1.170213 (12500 3800);
PAINT GREEN (12500 3800);
DISPLAY INVISIBLE (12500 3800);
FORCEPROP 2 LAST PATH I132
J 0
(12700 3975);
DISPLAY 1.021277 (12700 3975);
PAINT ORANGE (12700 3975);
DISPLAY INVISIBLE (12700 3975);
FORCEADD OFFPAGE..2
(12525 4000);
FORCEPROP 2 LAST $XR0 90 
J 0
(12714 4000);
DISPLAY 0.638298 (12714 4000);
PAINT MONO (12714 4000);
FORCEPROP 2 LAST CDS_LIB mstr_standard
J 0
(12525 4000);
PAINT ORANGE (12525 4000);
DISPLAY INVISIBLE (12525 4000);
FORCEPROP 1 LAST OFFPAGE TRUE
J 0
(12850 3875);
DISPLAY 0.872340 (12850 3875);
PAINT GREEN (12850 3875);
DISPLAY INVISIBLE (12850 3875);
FORCEPROP 1 LAST COMMENT_BODY TRUE
J 0
(12480 3905);
DISPLAY 0.872340 (12480 3905);
PAINT GREEN (12480 3905);
DISPLAY INVISIBLE (12480 3905);
FORCEPROP 2 LAST PATH I133
J 0
(12700 4075);
DISPLAY 1.021277 (12700 4075);
PAINT ORANGE (12700 4075);
DISPLAY INVISIBLE (12700 4075);
FORCEADD OFFPAGE..4
(12525 3850);
FORCEPROP 2 LAST $XR0 114 
J 0
(12711 3850);
DISPLAY 0.638298 (12711 3850);
PAINT MONO (12711 3850);
FORCEPROP 2 LAST $XR1 21 
J 0
(12831 3850);
DISPLAY 0.638298 (12831 3850);
PAINT MONO (12831 3850);
FORCEPROP 2 LAST CDS_LIB mstr_standard
J 0
(12525 3850);
PAINT ORANGE (12525 3850);
DISPLAY INVISIBLE (12525 3850);
FORCEPROP 1 LAST OFFPAGE TRUE
J 0
(12850 3725);
DISPLAY 1.170213 (12850 3725);
PAINT GREEN (12850 3725);
DISPLAY INVISIBLE (12850 3725);
FORCEPROP 1 LAST COMMENT_BODY TRUE
J 0
(12500 3750);
DISPLAY 1.170213 (12500 3750);
PAINT GREEN (12500 3750);
DISPLAY INVISIBLE (12500 3750);
FORCEPROP 2 LAST PATH I134
J 0
(12700 3925);
DISPLAY 1.021277 (12700 3925);
PAINT ORANGE (12700 3925);
DISPLAY INVISIBLE (12700 3925);
FORCEADD OFFPAGE..2
(13575 900);
FORCEPROP 2 LAST $XR0 112 
J 0
(13764 900);
DISPLAY 0.638298 (13764 900);
PAINT MONO (13764 900);
FORCEPROP 2 LAST $XR1 118 
J 0
(13884 900);
DISPLAY 0.638298 (13884 900);
PAINT MONO (13884 900);
FORCEPROP 2 LAST $XR2 144 
J 0
(14004 900);
DISPLAY 0.638298 (14004 900);
PAINT MONO (14004 900);
FORCEPROP 2 LAST $XR3 190 
J 0
(14124 900);
DISPLAY 0.638298 (14124 900);
PAINT MONO (14124 900);
FORCEPROP 2 LAST CDS_LIB mstr_standard
J 0
(13575 900);
PAINT ORANGE (13575 900);
DISPLAY INVISIBLE (13575 900);
FORCEPROP 1 LAST OFFPAGE TRUE
J 0
(13900 775);
DISPLAY 1.170213 (13900 775);
PAINT GREEN (13900 775);
DISPLAY INVISIBLE (13900 775);
FORCEPROP 1 LAST COMMENT_BODY TRUE
J 0
(13530 805);
DISPLAY 1.170213 (13530 805);
PAINT GREEN (13530 805);
DISPLAY INVISIBLE (13530 805);
FORCEPROP 2 LAST PATH I135
J 0
(13750 975);
DISPLAY 1.021277 (13750 975);
PAINT ORANGE (13750 975);
DISPLAY INVISIBLE (13750 975);
FORCEADD OFFPAGE..4
(12525 2300);
FORCEPROP 2 LAST $XR0 90 
J 0
(12711 2300);
DISPLAY 0.638298 (12711 2300);
PAINT MONO (12711 2300);
FORCEPROP 2 LAST CDS_LIB mstr_standard
J 0
(12525 2300);
PAINT ORANGE (12525 2300);
DISPLAY INVISIBLE (12525 2300);
FORCEPROP 1 LAST OFFPAGE TRUE
J 0
(12850 2175);
DISPLAY 1.170213 (12850 2175);
PAINT GREEN (12850 2175);
DISPLAY INVISIBLE (12850 2175);
FORCEPROP 1 LAST COMMENT_BODY TRUE
J 0
(12500 2200);
DISPLAY 1.170213 (12500 2200);
PAINT GREEN (12500 2200);
DISPLAY INVISIBLE (12500 2200);
FORCEPROP 2 LAST PATH I138
J 0
(12700 2375);
DISPLAY 1.021277 (12700 2375);
PAINT ORANGE (12700 2375);
DISPLAY INVISIBLE (12700 2375);
FORCEADD OFFPAGE..4
(12525 2250);
FORCEPROP 2 LAST $XR0 90 
J 0
(12711 2250);
DISPLAY 0.638298 (12711 2250);
PAINT MONO (12711 2250);
FORCEPROP 2 LAST CDS_LIB mstr_standard
J 0
(12525 2250);
PAINT ORANGE (12525 2250);
DISPLAY INVISIBLE (12525 2250);
FORCEPROP 1 LAST OFFPAGE TRUE
J 0
(12850 2125);
DISPLAY 1.170213 (12850 2125);
PAINT GREEN (12850 2125);
DISPLAY INVISIBLE (12850 2125);
FORCEPROP 1 LAST COMMENT_BODY TRUE
J 0
(12500 2150);
DISPLAY 1.170213 (12500 2150);
PAINT GREEN (12500 2150);
DISPLAY INVISIBLE (12500 2150);
FORCEPROP 2 LAST PATH I139
J 0
(12700 2325);
DISPLAY 1.021277 (12700 2325);
PAINT ORANGE (12700 2325);
DISPLAY INVISIBLE (12700 2325);
FORCEADD OFFPAGE..2
(13750 3600);
FORCEPROP 2 LAST $XR0 193 
J 0
(13939 3600);
DISPLAY 0.638298 (13939 3600);
PAINT MONO (13939 3600);
FORCEPROP 2 LAST $XR1 223 
J 0
(14059 3600);
DISPLAY 0.638298 (14059 3600);
PAINT MONO (14059 3600);
FORCEPROP 2 LAST $XR2 226 
J 0
(14179 3600);
DISPLAY 0.638298 (14179 3600);
PAINT MONO (14179 3600);
FORCEPROP 2 LAST CDS_LIB mstr_standard
J 0
(13750 3600);
PAINT MONO (13750 3600);
DISPLAY INVISIBLE (13750 3600);
FORCEPROP 1 LAST OFFPAGE TRUE
J 0
(14075 3475);
DISPLAY 1.170213 (14075 3475);
PAINT GREEN (14075 3475);
DISPLAY INVISIBLE (14075 3475);
FORCEPROP 1 LAST COMMENT_BODY TRUE
J 0
(13705 3505);
DISPLAY 1.170213 (13705 3505);
PAINT GREEN (13705 3505);
DISPLAY INVISIBLE (13705 3505);
FORCEPROP 2 LAST PATH I14
J 0
(13925 3675);
DISPLAY 1.021277 (13925 3675);
PAINT ORANGE (13925 3675);
DISPLAY INVISIBLE (13925 3675);
FORCEADD RES..2
R 2
(6800 2650);
FORCEPROP 1 LAST LOCATION R7P17
J 2
(6755 2775);
DISPLAY 0.617021 (6755 2775);
PAINT AQUA (6755 2775);
FORCEPROP 1 LAST PART_NUMBER G21796-365
J 2
(6760 2525);
DISPLAY 0.617021 (6760 2525);
PAINT BLUE (6760 2525);
FORCEPROP 1 LAST VALUE 90.9
J 2
(6755 2725);
DISPLAY 0.617021 (6755 2725);
PAINT SKYBLUE (6755 2725);
FORCEPROP 1 LAST TOLERANCE 1%
J 2
(6755 2675);
DISPLAY 0.617021 (6755 2675);
PAINT SKYBLUE (6755 2675);
FORCEPROP 1 LAST PACK_TYPE 0402
J 2
(6760 2475);
DISPLAY 0.617021 (6760 2475);
PAINT SKYBLUE (6760 2475);
FORCEPROP 1 LAST MATERIAL CHIP
J 2
(6760 2575);
DISPLAY 0.617021 (6760 2575);
PAINT SKYBLUE (6760 2575);
FORCEPROP 1 LAST WATTAGE 1/16W
J 2
(6760 2625);
DISPLAY 0.617021 (6760 2625);
PAINT SKYBLUE (6760 2625);
FORCEPROP 1 LASTPIN (6800 2550) $PN 2
J 2
(6795 2560);
DISPLAY 0.617021 (6795 2560);
PAINT ORANGE (6795 2560);
FORCEPROP 1 LASTPIN (6800 2750) $PN 1
J 2
(6795 2712);
DISPLAY 0.617021 (6795 2712);
PAINT ORANGE (6795 2712);
FORCEPROP 2 LAST SEC_TYPE 0402
J 0
(6750 2875);
DISPLAY 1.021277 (6750 2875);
PAINT ORANGE (6750 2875);
DISPLAY INVISIBLE (6750 2875);
FORCEPROP 2 LAST CDS_LIB mstr_discrete
J 0
(6800 2650);
PAINT ORANGE (6800 2650);
DISPLAY INVISIBLE (6800 2650);
FORCEPROP 2 LAST BOM_COST PROC_SOCKET
J 0
(6775 2875);
PAINT MONO (6775 2875);
DISPLAY INVISIBLE (6775 2875);
FORCEPROP 2 LAST SEC 1
J 0
(6750 2875);
DISPLAY 0.680851 (6750 2875);
PAINT MONO (6750 2875);
DISPLAY INVISIBLE (6750 2875);
FORCEPROP 2 LAST CDS_LOCATION R7P17
J 2
(6755 2775);
DISPLAY 0.617021 (6755 2775);
PAINT AQUA (6755 2775);
DISPLAY INVISIBLE (6755 2775);
FORCEPROP 1 LAST PATH I140
J 2
(6750 2825);
DISPLAY 0.978723 (6750 2825);
PAINT WHITE (6750 2825);
DISPLAY INVISIBLE (6750 2825);
FORCEPROP 2 LAST ROOM CPU1
J 0
(6775 2825);
PAINT MONO (6775 2825);
DISPLAY INVISIBLE (6775 2825);
FORCEADD OFFPAGE..4
(12525 1750);
FORCEPROP 2 LAST $XR0 97 
J 0
(12711 1750);
DISPLAY 0.638298 (12711 1750);
PAINT MONO (12711 1750);
FORCEPROP 2 LAST CDS_LIB mstr_standard
J 0
(12525 1750);
PAINT ORANGE (12525 1750);
DISPLAY INVISIBLE (12525 1750);
FORCEPROP 1 LAST OFFPAGE TRUE
J 0
(12850 1625);
DISPLAY 1.170213 (12850 1625);
PAINT GREEN (12850 1625);
DISPLAY INVISIBLE (12850 1625);
FORCEPROP 1 LAST COMMENT_BODY TRUE
J 0
(12500 1650);
DISPLAY 1.170213 (12500 1650);
PAINT GREEN (12500 1650);
DISPLAY INVISIBLE (12500 1650);
FORCEPROP 2 LAST PATH I145
J 0
(12700 1825);
DISPLAY 1.021277 (12700 1825);
PAINT ORANGE (12700 1825);
DISPLAY INVISIBLE (12700 1825);
FORCEADD OFFPAGE..4
(12525 1550);
FORCEPROP 2 LAST $XR0 90 
J 0
(12711 1550);
DISPLAY 0.638298 (12711 1550);
PAINT MONO (12711 1550);
FORCEPROP 2 LAST CDS_LIB mstr_standard
J 0
(12525 1550);
PAINT ORANGE (12525 1550);
DISPLAY INVISIBLE (12525 1550);
FORCEPROP 1 LAST OFFPAGE TRUE
J 0
(12850 1425);
DISPLAY 1.170213 (12850 1425);
PAINT GREEN (12850 1425);
DISPLAY INVISIBLE (12850 1425);
FORCEPROP 1 LAST COMMENT_BODY TRUE
J 0
(12500 1450);
DISPLAY 1.170213 (12500 1450);
PAINT GREEN (12500 1450);
DISPLAY INVISIBLE (12500 1450);
FORCEPROP 2 LAST PATH I146
J 0
(12700 1625);
DISPLAY 1.021277 (12700 1625);
PAINT ORANGE (12700 1625);
DISPLAY INVISIBLE (12700 1625);
FORCEADD OFFPAGE..5
(7950 3050);
FORCEPROP 2 LAST $XR0 100 
J 0
(7695 3050);
DISPLAY 0.638298 (7695 3050);
PAINT MONO (7695 3050);
FORCEPROP 2 LAST CDS_LIB mstr_standard
J 0
(7950 3050);
PAINT ORANGE (7950 3050);
DISPLAY INVISIBLE (7950 3050);
FORCEPROP 1 LAST OFFPAGE TRUE
J 0
(8275 2925);
DISPLAY 1.170213 (8275 2925);
PAINT GREEN (8275 2925);
DISPLAY INVISIBLE (8275 2925);
FORCEPROP 1 LAST COMMENT_BODY TRUE
J 0
(8050 2975);
DISPLAY 1.170213 (8050 2975);
PAINT GREEN (8050 2975);
DISPLAY INVISIBLE (8050 2975);
FORCEPROP 2 LAST PATH I148
J 0
(8000 3125);
DISPLAY 1.021277 (8000 3125);
PAINT ORANGE (8000 3125);
DISPLAY INVISIBLE (8000 3125);
FORCEADD OFFPAGE..5
(7950 3100);
FORCEPROP 2 LAST $XR0 100 
J 0
(7695 3100);
DISPLAY 0.638298 (7695 3100);
PAINT MONO (7695 3100);
FORCEPROP 2 LAST CDS_LIB mstr_standard
J 0
(7950 3100);
PAINT ORANGE (7950 3100);
DISPLAY INVISIBLE (7950 3100);
FORCEPROP 1 LAST OFFPAGE TRUE
J 0
(8275 2975);
DISPLAY 1.170213 (8275 2975);
PAINT GREEN (8275 2975);
DISPLAY INVISIBLE (8275 2975);
FORCEPROP 1 LAST COMMENT_BODY TRUE
J 0
(8050 3025);
DISPLAY 1.170213 (8050 3025);
PAINT GREEN (8050 3025);
DISPLAY INVISIBLE (8050 3025);
FORCEPROP 2 LAST PATH I149
J 0
(8000 3175);
DISPLAY 1.021277 (8000 3175);
PAINT ORANGE (8000 3175);
DISPLAY INVISIBLE (8000 3175);
FORCEADD OFFPAGE..4
(13750 3550);
FORCEPROP 2 LAST $XR0 193 
J 0
(13936 3550);
DISPLAY 0.638298 (13936 3550);
PAINT MONO (13936 3550);
FORCEPROP 2 LAST $XR1 223 
J 0
(14056 3550);
DISPLAY 0.638298 (14056 3550);
PAINT MONO (14056 3550);
FORCEPROP 2 LAST $XR2 226 
J 0
(14176 3550);
DISPLAY 0.638298 (14176 3550);
PAINT MONO (14176 3550);
FORCEPROP 2 LAST CDS_LIB mstr_standard
J 0
(13750 3550);
PAINT MONO (13750 3550);
DISPLAY INVISIBLE (13750 3550);
FORCEPROP 1 LAST OFFPAGE TRUE
J 0
(14075 3425);
DISPLAY 1.170213 (14075 3425);
PAINT GREEN (14075 3425);
DISPLAY INVISIBLE (14075 3425);
FORCEPROP 1 LAST COMMENT_BODY TRUE
J 0
(13725 3450);
DISPLAY 1.170213 (13725 3450);
PAINT GREEN (13725 3450);
DISPLAY INVISIBLE (13725 3450);
FORCEPROP 2 LAST PATH I15
J 0
(13925 3625);
DISPLAY 1.021277 (13925 3625);
PAINT ORANGE (13925 3625);
DISPLAY INVISIBLE (13925 3625);
FORCEADD OFFPAGE..5
(7950 3200);
FORCEPROP 2 LAST $XR0 100 
J 0
(7695 3200);
DISPLAY 0.638298 (7695 3200);
PAINT MONO (7695 3200);
FORCEPROP 2 LAST CDS_LIB mstr_standard
J 0
(7950 3200);
PAINT ORANGE (7950 3200);
DISPLAY INVISIBLE (7950 3200);
FORCEPROP 1 LAST OFFPAGE TRUE
J 0
(8275 3075);
DISPLAY 1.170213 (8275 3075);
PAINT GREEN (8275 3075);
DISPLAY INVISIBLE (8275 3075);
FORCEPROP 1 LAST COMMENT_BODY TRUE
J 0
(8050 3125);
DISPLAY 1.170213 (8050 3125);
PAINT GREEN (8050 3125);
DISPLAY INVISIBLE (8050 3125);
FORCEPROP 2 LAST PATH I150
J 0
(8000 3275);
DISPLAY 1.021277 (8000 3275);
PAINT ORANGE (8000 3275);
DISPLAY INVISIBLE (8000 3275);
FORCEADD OFFPAGE..5
(7950 3250);
FORCEPROP 2 LAST $XR0 100 
J 0
(7695 3250);
DISPLAY 0.638298 (7695 3250);
PAINT MONO (7695 3250);
FORCEPROP 2 LAST CDS_LIB mstr_standard
J 0
(7950 3250);
PAINT ORANGE (7950 3250);
DISPLAY INVISIBLE (7950 3250);
FORCEPROP 1 LAST OFFPAGE TRUE
J 0
(8275 3125);
DISPLAY 1.170213 (8275 3125);
PAINT GREEN (8275 3125);
DISPLAY INVISIBLE (8275 3125);
FORCEPROP 1 LAST COMMENT_BODY TRUE
J 0
(8050 3175);
DISPLAY 1.170213 (8050 3175);
PAINT GREEN (8050 3175);
DISPLAY INVISIBLE (8050 3175);
FORCEPROP 2 LAST PATH I151
J 0
(8000 3325);
DISPLAY 1.021277 (8000 3325);
PAINT ORANGE (8000 3325);
DISPLAY INVISIBLE (8000 3325);
FORCEADD SOCKET_P_MECH_A..1
(6875 4000);
FORCEPROP 1 LAST LOCATION XRU2
J 0
(6525 4075);
DISPLAY 0.617021 (6525 4075);
PAINT AQUA (6525 4075);
FORCEPROP 1 LAST PART_NUMBER H37604-101
J 0
(6525 3900);
DISPLAY 0.617021 (6525 3900);
PAINT BLUE (6525 3900);
FORCEPROP 1 LAST PACK_TYPE RIGHT
J 0
(6980 3975);
DISPLAY 0.617021 (6980 3975);
PAINT SKYBLUE (6980 3975);
FORCEPROP 1 LAST MATERIAL PLASTIC
J 0
(6525 4125);
DISPLAY 0.617021 (6525 4125);
PAINT SKYBLUE (6525 4125);
FORCEPROP 1 LAST SKT_NUMBER P0
J 0
(6550 3975);
DISPLAY 0.808511 (6550 3975);
PAINT GREEN (6550 3975);
FORCEPROP 2 LAST CDS_LIB chpset_lib
J 0
(6875 4000);
PAINT ORANGE (6875 4000);
DISPLAY INVISIBLE (6875 4000);
FORCEPROP 0 LAST BOM_COST PROC_SOCKET
J 0
(6525 4325);
DISPLAY 1.021277 (6525 4325);
PAINT ORANGE (6525 4325);
DISPLAY INVISIBLE (6525 4325);
FORCEPROP 2 LAST CDS_LOCATION XRU2
J 0
(6525 4075);
DISPLAY 0.617021 (6525 4075);
PAINT AQUA (6525 4075);
DISPLAY INVISIBLE (6525 4075);
FORCEPROP 1 LAST PATH I152
J 0
(6875 4120);
DISPLAY 0.872340 (6875 4120);
PAINT WHITE (6875 4120);
DISPLAY INVISIBLE (6875 4120);
FORCEPROP 0 LAST ROOM CPU1
J 0
(6525 4225);
DISPLAY 1.021277 (6525 4225);
PAINT ORANGE (6525 4225);
DISPLAY INVISIBLE (6525 4225);
FORCEADD SOCKET_P_MECH_A..1
(6875 3725);
FORCEPROP 1 LAST LOCATION XLU2
J 0
(6525 3800);
DISPLAY 0.617021 (6525 3800);
PAINT AQUA (6525 3800);
FORCEPROP 1 LAST PART_NUMBER H37604-201
J 0
(6525 3625);
DISPLAY 0.617021 (6525 3625);
PAINT BLUE (6525 3625);
FORCEPROP 1 LAST PACK_TYPE LEFT
J 0
(6980 3700);
DISPLAY 0.617021 (6980 3700);
PAINT SKYBLUE (6980 3700);
FORCEPROP 1 LAST MATERIAL PLASTIC
J 0
(6525 3850);
DISPLAY 0.617021 (6525 3850);
PAINT SKYBLUE (6525 3850);
FORCEPROP 1 LAST SKT_NUMBER P0
J 0
(6550 3700);
DISPLAY 0.808511 (6550 3700);
PAINT GREEN (6550 3700);
FORCEPROP 2 LAST CDS_LIB chpset_lib
J 0
(6875 3725);
PAINT ORANGE (6875 3725);
DISPLAY INVISIBLE (6875 3725);
FORCEPROP 0 LAST BOM_COST PROC_SOCKET
J 0
(6525 4050);
DISPLAY 1.021277 (6525 4050);
PAINT ORANGE (6525 4050);
DISPLAY INVISIBLE (6525 4050);
FORCEPROP 2 LAST CDS_LOCATION XLU2
J 0
(6525 3800);
DISPLAY 0.617021 (6525 3800);
PAINT AQUA (6525 3800);
DISPLAY INVISIBLE (6525 3800);
FORCEPROP 1 LAST PATH I153
J 0
(6875 3845);
DISPLAY 0.872340 (6875 3845);
PAINT WHITE (6875 3845);
DISPLAY INVISIBLE (6875 3845);
FORCEPROP 0 LAST ROOM CPU1
J 0
(6525 3950);
DISPLAY 1.021277 (6525 3950);
PAINT ORANGE (6525 3950);
DISPLAY INVISIBLE (6525 3950);
FORCEADD RES..2
R 2
(7400 1425);
FORCEPROP 1 LAST LOCATION R3D4
J 2
(7355 1550);
DISPLAY 0.617021 (7355 1550);
PAINT AQUA (7355 1550);
FORCEPROP 1 LAST PART_NUMBER G21796-047
J 2
(7435 1300);
DISPLAY 0.617021 (7435 1300);
PAINT BLUE (7435 1300);
FORCEPROP 1 LAST VALUE 49.9
J 2
(7355 1500);
DISPLAY 0.617021 (7355 1500);
PAINT SKYBLUE (7355 1500);
FORCEPROP 1 LAST TOLERANCE 1%
J 2
(7355 1450);
DISPLAY 0.617021 (7355 1450);
PAINT SKYBLUE (7355 1450);
FORCEPROP 1 LAST PACK_TYPE 0402
J 2
(7360 1250);
DISPLAY 0.617021 (7360 1250);
PAINT SKYBLUE (7360 1250);
FORCEPROP 1 LAST MATERIAL CHIP
J 2
(7360 1350);
DISPLAY 0.617021 (7360 1350);
PAINT SKYBLUE (7360 1350);
FORCEPROP 1 LAST WATTAGE 1/16W
J 2
(7360 1400);
DISPLAY 0.617021 (7360 1400);
PAINT SKYBLUE (7360 1400);
FORCEPROP 1 LASTPIN (7400 1325) $PN 2
J 2
(7395 1335);
DISPLAY 0.617021 (7395 1335);
PAINT ORANGE (7395 1335);
FORCEPROP 1 LASTPIN (7400 1525) $PN 1
J 2
(7395 1487);
DISPLAY 0.617021 (7395 1487);
PAINT ORANGE (7395 1487);
FORCEPROP 2 LAST CDS_LIB mstr_discrete
J 0
(7400 1425);
PAINT ORANGE (7400 1425);
DISPLAY INVISIBLE (7400 1425);
FORCEPROP 2 LAST SEC_TYPE 0402
J 0
(7350 1650);
DISPLAY 1.021277 (7350 1650);
PAINT ORANGE (7350 1650);
DISPLAY INVISIBLE (7350 1650);
FORCEPROP 2 LAST BOM_COST PROC_SOCKET
J 0
(7375 1650);
PAINT MONO (7375 1650);
DISPLAY INVISIBLE (7375 1650);
FORCEPROP 2 LAST SEC 1
J 0
(7350 1650);
DISPLAY 0.680851 (7350 1650);
PAINT MONO (7350 1650);
DISPLAY INVISIBLE (7350 1650);
FORCEPROP 2 LAST CDS_LOCATION R3D4
J 2
(7355 1550);
DISPLAY 0.617021 (7355 1550);
PAINT AQUA (7355 1550);
DISPLAY INVISIBLE (7355 1550);
FORCEPROP 1 LAST PATH I155
J 2
(7350 1600);
DISPLAY 0.978723 (7350 1600);
PAINT WHITE (7350 1600);
DISPLAY INVISIBLE (7350 1600);
FORCEPROP 2 LAST ROOM CPU1
J 0
(7375 1600);
PAINT MONO (7375 1600);
DISPLAY INVISIBLE (7375 1600);
FORCEADD RES..1
(11925 3850);
FORCEPROP 1 LAST LOCATION R7P26
J 0
(11900 3950);
DISPLAY 0.617021 (11900 3950);
PAINT AQUA (11900 3950);
FORCEPROP 1 LAST PART_NUMBER G21796-047
J 0
(12200 3800);
DISPLAY 0.617021 (12200 3800);
PAINT BLUE (12200 3800);
FORCEPROP 1 LAST VALUE 49.9
J 2
(11900 3800);
DISPLAY 0.617021 (11900 3800);
PAINT SKYBLUE (11900 3800);
FORCEPROP 1 LAST TOLERANCE 1%
J 0
(11925 3800);
DISPLAY 0.617021 (11925 3800);
PAINT SKYBLUE (11925 3800);
FORCEPROP 1 LAST PACK_TYPE 0402
J 0
(12100 3800);
DISPLAY 0.617021 (12100 3800);
PAINT SKYBLUE (12100 3800);
FORCEPROP 1 LAST MATERIAL CHIP
J 0
(12000 3800);
DISPLAY 0.617021 (12000 3800);
PAINT SKYBLUE (12000 3800);
FORCEPROP 1 LAST WATTAGE 1/16W
J 2
(11800 3800);
DISPLAY 0.617021 (11800 3800);
PAINT SKYBLUE (11800 3800);
FORCEPROP 1 LASTPIN (12025 3850) $PN 2
J 0
(11987 3862);
DISPLAY 0.617021 (11987 3862);
PAINT ORANGE (11987 3862);
FORCEPROP 1 LASTPIN (11825 3850) $PN 1
J 0
(11837 3862);
DISPLAY 0.617021 (11837 3862);
PAINT ORANGE (11837 3862);
FORCEPROP 2 LAST SEC_TYPE 0402
J 0
(11875 4050);
DISPLAY 1.021277 (11875 4050);
PAINT ORANGE (11875 4050);
DISPLAY INVISIBLE (11875 4050);
FORCEPROP 2 LAST CDS_LIB mstr_discrete
J 0
(11925 3850);
PAINT ORANGE (11925 3850);
DISPLAY INVISIBLE (11925 3850);
FORCEPROP 2 LAST BOM_COST PROC_SOCKET
J 0
(11900 4050);
PAINT MONO (11900 4050);
DISPLAY INVISIBLE (11900 4050);
FORCEPROP 2 LAST SEC 1
J 0
(11875 4050);
DISPLAY 0.680851 (11875 4050);
PAINT MONO (11875 4050);
DISPLAY INVISIBLE (11875 4050);
FORCEPROP 2 LAST CDS_LOCATION R7P26
J 0
(11900 3950);
DISPLAY 0.617021 (11900 3950);
PAINT AQUA (11900 3950);
DISPLAY INVISIBLE (11900 3950);
FORCEPROP 1 LAST PATH I156
J 0
(11875 4000);
DISPLAY 0.978723 (11875 4000);
PAINT WHITE (11875 4000);
DISPLAY INVISIBLE (11875 4000);
FORCEPROP 2 LAST ROOM CPU1
J 0
(11900 4000);
PAINT MONO (11900 4000);
DISPLAY INVISIBLE (11900 4000);
FORCEADD RES..2
(12875 2350);
FORCEPROP 1 LAST LOCATION R8N1
J 2
(13025 2475);
DISPLAY 0.617021 (13025 2475);
PAINT AQUA (13025 2475);
FORCEPROP 1 LAST PART_NUMBER G21796-336
J 0
(12915 2225);
DISPLAY 0.617021 (12915 2225);
PAINT BLUE (12915 2225);
FORCEPROP 1 LAST VALUE 1.8K
J 0
(12920 2425);
DISPLAY 0.617021 (12920 2425);
PAINT SKYBLUE (12920 2425);
FORCEPROP 1 LAST TOLERANCE 1%
J 0
(12920 2375);
DISPLAY 0.617021 (12920 2375);
PAINT SKYBLUE (12920 2375);
FORCEPROP 1 LAST PACK_TYPE 0402
J 0
(12915 2175);
DISPLAY 0.617021 (12915 2175);
PAINT SKYBLUE (12915 2175);
FORCEPROP 1 LAST MATERIAL CHIP
J 0
(12915 2275);
DISPLAY 0.617021 (12915 2275);
PAINT SKYBLUE (12915 2275);
FORCEPROP 1 LAST WATTAGE 1/16W
J 0
(12915 2325);
DISPLAY 0.617021 (12915 2325);
PAINT SKYBLUE (12915 2325);
FORCEPROP 1 LASTPIN (12875 2250) $PN 2
J 0
(12880 2260);
DISPLAY 0.617021 (12880 2260);
PAINT ORANGE (12880 2260);
FORCEPROP 1 LASTPIN (12875 2450) $PN 1
J 0
(12880 2412);
DISPLAY 0.617021 (12880 2412);
PAINT ORANGE (12880 2412);
FORCEPROP 2 LAST SEC_TYPE 0402
J 0
(12925 2575);
DISPLAY 1.021277 (12925 2575);
PAINT ORANGE (12925 2575);
DISPLAY INVISIBLE (12925 2575);
FORCEPROP 2 LAST CDS_LIB mstr_discrete
J 0
(12875 2350);
PAINT ORANGE (12875 2350);
DISPLAY INVISIBLE (12875 2350);
FORCEPROP 2 LAST BOM_COST PROC_SOCKET
J 0
(13025 2575);
PAINT MONO (13025 2575);
DISPLAY INVISIBLE (13025 2575);
FORCEPROP 2 LAST SEC 1
J 0
(12925 2575);
DISPLAY 0.680851 (12925 2575);
PAINT MONO (12925 2575);
DISPLAY INVISIBLE (12925 2575);
FORCEPROP 2 LAST CDS_LOCATION R8N1
J 2
(13025 2475);
DISPLAY 0.617021 (13025 2475);
PAINT AQUA (13025 2475);
DISPLAY INVISIBLE (13025 2475);
FORCEPROP 1 LAST PATH I157
J 0
(12925 2525);
DISPLAY 0.978723 (12925 2525);
PAINT WHITE (12925 2525);
DISPLAY INVISIBLE (12925 2525);
FORCEPROP 2 LAST ROOM CPU1
J 0
(13025 2525);
PAINT MONO (13025 2525);
DISPLAY INVISIBLE (13025 2525);
FORCEADD RES..2
(13075 2350);
FORCEPROP 1 LAST LOCATION R8N4
J 0
(13120 2475);
DISPLAY 0.617021 (13120 2475);
PAINT AQUA (13120 2475);
FORCEPROP 1 LAST PART_NUMBER G21796-336
J 0
(13115 2225);
DISPLAY 0.617021 (13115 2225);
PAINT BLUE (13115 2225);
FORCEPROP 1 LAST VALUE 1.8K
J 0
(13120 2425);
DISPLAY 0.617021 (13120 2425);
PAINT SKYBLUE (13120 2425);
FORCEPROP 1 LAST TOLERANCE 1%
J 0
(13120 2375);
DISPLAY 0.617021 (13120 2375);
PAINT SKYBLUE (13120 2375);
FORCEPROP 1 LAST PACK_TYPE 0402
J 0
(13115 2175);
DISPLAY 0.617021 (13115 2175);
PAINT SKYBLUE (13115 2175);
FORCEPROP 1 LAST MATERIAL CHIP
J 0
(13115 2275);
DISPLAY 0.617021 (13115 2275);
PAINT SKYBLUE (13115 2275);
FORCEPROP 1 LAST WATTAGE 1/16W
J 0
(13115 2325);
DISPLAY 0.617021 (13115 2325);
PAINT SKYBLUE (13115 2325);
FORCEPROP 1 LASTPIN (13075 2250) $PN 2
J 0
(13080 2260);
DISPLAY 0.617021 (13080 2260);
PAINT ORANGE (13080 2260);
FORCEPROP 1 LASTPIN (13075 2450) $PN 1
J 0
(13080 2412);
DISPLAY 0.617021 (13080 2412);
PAINT ORANGE (13080 2412);
FORCEPROP 2 LAST SEC_TYPE 0402
J 0
(13125 2575);
DISPLAY 1.021277 (13125 2575);
PAINT ORANGE (13125 2575);
DISPLAY INVISIBLE (13125 2575);
FORCEPROP 2 LAST CDS_LIB mstr_discrete
J 0
(13075 2350);
PAINT ORANGE (13075 2350);
DISPLAY INVISIBLE (13075 2350);
FORCEPROP 2 LAST BOM_COST PROC_SOCKET
J 0
(13125 2575);
PAINT MONO (13125 2575);
DISPLAY INVISIBLE (13125 2575);
FORCEPROP 2 LAST SEC 1
J 0
(13125 2575);
DISPLAY 0.680851 (13125 2575);
PAINT MONO (13125 2575);
DISPLAY INVISIBLE (13125 2575);
FORCEPROP 2 LAST CDS_LOCATION R8N4
J 0
(13120 2475);
DISPLAY 0.617021 (13120 2475);
PAINT AQUA (13120 2475);
DISPLAY INVISIBLE (13120 2475);
FORCEPROP 1 LAST PATH I158
J 0
(13125 2525);
DISPLAY 0.978723 (13125 2525);
PAINT WHITE (13125 2525);
DISPLAY INVISIBLE (13125 2525);
FORCEPROP 2 LAST ROOM CPU1
J 0
(13125 2525);
PAINT MONO (13125 2525);
DISPLAY INVISIBLE (13125 2525);
FORCEADD RES..2
(13275 2350);
FORCEPROP 1 LAST LOCATION R8N3
J 0
(13320 2475);
DISPLAY 0.617021 (13320 2475);
PAINT AQUA (13320 2475);
FORCEPROP 1 LAST PART_NUMBER G21796-016
J 0
(13315 2225);
DISPLAY 0.617021 (13315 2225);
PAINT BLUE (13315 2225);
FORCEPROP 1 LAST VALUE 10.0K
J 0
(13320 2425);
DISPLAY 0.617021 (13320 2425);
PAINT SKYBLUE (13320 2425);
FORCEPROP 1 LAST TOLERANCE 1%
J 0
(13320 2375);
DISPLAY 0.617021 (13320 2375);
PAINT SKYBLUE (13320 2375);
FORCEPROP 1 LAST PACK_TYPE 0402
J 0
(13315 2175);
DISPLAY 0.617021 (13315 2175);
PAINT SKYBLUE (13315 2175);
FORCEPROP 1 LAST MATERIAL CHIP
J 0
(13315 2275);
DISPLAY 0.617021 (13315 2275);
PAINT SKYBLUE (13315 2275);
FORCEPROP 1 LAST WATTAGE 1/16W
J 0
(13315 2325);
DISPLAY 0.617021 (13315 2325);
PAINT SKYBLUE (13315 2325);
FORCEPROP 1 LASTPIN (13275 2250) $PN 2
J 0
(13280 2260);
DISPLAY 0.617021 (13280 2260);
PAINT ORANGE (13280 2260);
FORCEPROP 1 LASTPIN (13275 2450) $PN 1
J 0
(13280 2412);
DISPLAY 0.617021 (13280 2412);
PAINT ORANGE (13280 2412);
FORCEPROP 2 LAST SEC_TYPE 0402
J 0
(13325 2575);
DISPLAY 1.021277 (13325 2575);
PAINT ORANGE (13325 2575);
DISPLAY INVISIBLE (13325 2575);
FORCEPROP 2 LAST CDS_LIB mstr_discrete
J 0
(13275 2350);
PAINT ORANGE (13275 2350);
DISPLAY INVISIBLE (13275 2350);
FORCEPROP 2 LAST BOM_COST PROC_SOCKET
J 0
(13325 2575);
PAINT MONO (13325 2575);
DISPLAY INVISIBLE (13325 2575);
FORCEPROP 2 LAST SEC 1
J 0
(13325 2575);
DISPLAY 0.680851 (13325 2575);
PAINT MONO (13325 2575);
DISPLAY INVISIBLE (13325 2575);
FORCEPROP 2 LAST CDS_LOCATION R8N3
J 0
(13320 2475);
DISPLAY 0.617021 (13320 2475);
PAINT AQUA (13320 2475);
DISPLAY INVISIBLE (13320 2475);
FORCEPROP 1 LAST PATH I159
J 0
(13325 2525);
DISPLAY 0.978723 (13325 2525);
PAINT WHITE (13325 2525);
DISPLAY INVISIBLE (13325 2525);
FORCEPROP 2 LAST ROOM CPU1
J 0
(13325 2525);
PAINT MONO (13325 2525);
DISPLAY INVISIBLE (13325 2525);
FORCEADD OFFPAGE..2
(13750 3450);
FORCEPROP 2 LAST $XR0 193 
J 0
(13939 3450);
DISPLAY 0.638298 (13939 3450);
PAINT MONO (13939 3450);
FORCEPROP 2 LAST $XR1 206 
J 0
(14059 3450);
DISPLAY 0.638298 (14059 3450);
PAINT MONO (14059 3450);
FORCEPROP 2 LAST $XR2 213 
J 0
(14179 3450);
DISPLAY 0.638298 (14179 3450);
PAINT MONO (14179 3450);
FORCEPROP 2 LAST CDS_LIB mstr_standard
J 0
(13750 3450);
PAINT MONO (13750 3450);
DISPLAY INVISIBLE (13750 3450);
FORCEPROP 1 LAST OFFPAGE TRUE
J 0
(14075 3325);
DISPLAY 1.170213 (14075 3325);
PAINT GREEN (14075 3325);
DISPLAY INVISIBLE (14075 3325);
FORCEPROP 1 LAST COMMENT_BODY TRUE
J 0
(13705 3355);
DISPLAY 1.170213 (13705 3355);
PAINT GREEN (13705 3355);
DISPLAY INVISIBLE (13705 3355);
FORCEPROP 2 LAST PATH I16
J 0
(13925 3525);
DISPLAY 1.021277 (13925 3525);
PAINT ORANGE (13925 3525);
DISPLAY INVISIBLE (13925 3525);
FORCEADD RES..2
(13475 2350);
FORCEPROP 1 LAST LOCATION R8N5
J 0
(13520 2475);
DISPLAY 0.617021 (13520 2475);
PAINT AQUA (13520 2475);
FORCEPROP 1 LAST PART_NUMBER G21796-016
J 0
(13515 2225);
DISPLAY 0.617021 (13515 2225);
PAINT BLUE (13515 2225);
FORCEPROP 1 LAST VALUE 10.0K
J 0
(13520 2425);
DISPLAY 0.617021 (13520 2425);
PAINT SKYBLUE (13520 2425);
FORCEPROP 1 LAST TOLERANCE 1%
J 0
(13520 2375);
DISPLAY 0.617021 (13520 2375);
PAINT SKYBLUE (13520 2375);
FORCEPROP 1 LAST PACK_TYPE 0402
J 0
(13515 2175);
DISPLAY 0.617021 (13515 2175);
PAINT SKYBLUE (13515 2175);
FORCEPROP 1 LAST MATERIAL CHIP
J 0
(13515 2275);
DISPLAY 0.617021 (13515 2275);
PAINT SKYBLUE (13515 2275);
FORCEPROP 1 LAST WATTAGE 1/16W
J 0
(13515 2325);
DISPLAY 0.617021 (13515 2325);
PAINT SKYBLUE (13515 2325);
FORCEPROP 1 LASTPIN (13475 2250) $PN 2
J 0
(13480 2260);
DISPLAY 0.617021 (13480 2260);
PAINT ORANGE (13480 2260);
FORCEPROP 1 LASTPIN (13475 2450) $PN 1
J 0
(13480 2412);
DISPLAY 0.617021 (13480 2412);
PAINT ORANGE (13480 2412);
FORCEPROP 2 LAST SEC_TYPE 0402
J 0
(13525 2575);
DISPLAY 1.021277 (13525 2575);
PAINT ORANGE (13525 2575);
DISPLAY INVISIBLE (13525 2575);
FORCEPROP 2 LAST CDS_LIB mstr_discrete
J 0
(13475 2350);
PAINT ORANGE (13475 2350);
DISPLAY INVISIBLE (13475 2350);
FORCEPROP 2 LAST BOM_COST PROC_SOCKET
J 0
(13525 2575);
PAINT MONO (13525 2575);
DISPLAY INVISIBLE (13525 2575);
FORCEPROP 2 LAST SEC 1
J 0
(13525 2575);
DISPLAY 0.680851 (13525 2575);
PAINT MONO (13525 2575);
DISPLAY INVISIBLE (13525 2575);
FORCEPROP 2 LAST CDS_LOCATION R8N5
J 0
(13520 2475);
DISPLAY 0.617021 (13520 2475);
PAINT AQUA (13520 2475);
DISPLAY INVISIBLE (13520 2475);
FORCEPROP 1 LAST PATH I160
J 0
(13525 2525);
DISPLAY 0.978723 (13525 2525);
PAINT WHITE (13525 2525);
DISPLAY INVISIBLE (13525 2525);
FORCEPROP 2 LAST ROOM CPU1
J 0
(13525 2525);
PAINT MONO (13525 2525);
DISPLAY INVISIBLE (13525 2525);
FORCEADD RES..2
(13675 2350);
FORCEPROP 1 LAST LOCATION R8N2
J 0
(13720 2475);
DISPLAY 0.617021 (13720 2475);
PAINT AQUA (13720 2475);
FORCEPROP 1 LAST PART_NUMBER G21796-016
J 0
(13715 2225);
DISPLAY 0.617021 (13715 2225);
PAINT BLUE (13715 2225);
FORCEPROP 1 LAST TOLERANCE 1%
J 0
(13720 2375);
DISPLAY 0.617021 (13720 2375);
PAINT SKYBLUE (13720 2375);
FORCEPROP 1 LAST WATTAGE 1/16W
J 0
(13715 2325);
DISPLAY 0.617021 (13715 2325);
PAINT SKYBLUE (13715 2325);
FORCEPROP 1 LASTPIN (13675 2250) $PN 2
J 0
(13680 2260);
DISPLAY 0.617021 (13680 2260);
PAINT ORANGE (13680 2260);
FORCEPROP 1 LASTPIN (13675 2450) $PN 1
J 0
(13680 2412);
DISPLAY 0.617021 (13680 2412);
PAINT ORANGE (13680 2412);
FORCEPROP 1 LAST PACK_TYPE 0402
J 0
(13715 2175);
DISPLAY 0.617021 (13715 2175);
PAINT SKYBLUE (13715 2175);
FORCEPROP 1 LAST MATERIAL CHIP
J 0
(13715 2275);
DISPLAY 0.617021 (13715 2275);
PAINT SKYBLUE (13715 2275);
FORCEPROP 1 LAST VALUE 10.0K
J 0
(13720 2425);
DISPLAY 0.617021 (13720 2425);
PAINT SKYBLUE (13720 2425);
FORCEPROP 2 LAST SEC_TYPE 0402
J 0
(13725 2575);
DISPLAY 1.021277 (13725 2575);
PAINT ORANGE (13725 2575);
DISPLAY INVISIBLE (13725 2575);
FORCEPROP 2 LAST CDS_LIB mstr_discrete
J 0
(13675 2350);
PAINT ORANGE (13675 2350);
DISPLAY INVISIBLE (13675 2350);
FORCEPROP 2 LAST BOM_COST PROC_SOCKET
J 0
(13725 2575);
PAINT MONO (13725 2575);
DISPLAY INVISIBLE (13725 2575);
FORCEPROP 2 LAST SEC 1
J 0
(13725 2575);
DISPLAY 0.680851 (13725 2575);
PAINT MONO (13725 2575);
DISPLAY INVISIBLE (13725 2575);
FORCEPROP 2 LAST CDS_LOCATION R8N2
J 0
(13720 2475);
DISPLAY 0.617021 (13720 2475);
PAINT AQUA (13720 2475);
DISPLAY INVISIBLE (13720 2475);
FORCEPROP 1 LAST PATH I161
J 0
(13725 2525);
DISPLAY 0.978723 (13725 2525);
PAINT WHITE (13725 2525);
DISPLAY INVISIBLE (13725 2525);
FORCEPROP 2 LAST ROOM CPU1
J 0
(13725 2525);
PAINT MONO (13725 2525);
DISPLAY INVISIBLE (13725 2525);
FORCEADD P3V3_STBY..1
(13675 2700);
FORCEPROP 3 LASTPIN (13675 2650) SIG_NAME P3V3_STBY\g
J 0
(13685 2660);
DISPLAY 0.659574 (13685 2660);
PAINT MONO (13685 2660);
DISPLAY INVISIBLE (13685 2660);
FORCEPROP 1 LAST VOLTAGE 3.3V
J 0
(13630 2657);
DISPLAY 0.340426 (13630 2657);
PAINT SKYBLUE (13630 2657);
DISPLAY INVISIBLE (13630 2657);
FORCEPROP 2 LAST CDS_LIB mstr_symbols
J 0
(13675 2700);
PAINT ORANGE (13675 2700);
DISPLAY INVISIBLE (13675 2700);
FORCEPROP 1 LAST SIZE 1B
J 0
(13720 2722);
DISPLAY 0.340426 (13720 2722);
PAINT GREEN (13720 2722);
DISPLAY INVISIBLE (13720 2722);
FORCEPROP 1 LAST BODY_TYPE PLUMBING
J 0
(13630 2657);
DISPLAY 0.340426 (13630 2657);
PAINT GREEN (13630 2657);
DISPLAY INVISIBLE (13630 2657);
FORCEPROP 1 LAST PATH I162
J 0
(13720 2702);
DISPLAY 0.340426 (13720 2702);
PAINT GREEN (13720 2702);
DISPLAY INVISIBLE (13720 2702);
FORCEPROP 1 LAST HDL_POWER P3V3_STBY
J 0
(13375 2575);
DISPLAY 0.872340 (13375 2575);
PAINT GREEN (13375 2575);
DISPLAY INVISIBLE (13375 2575);
FORCEADD OFFPAGE..2
(13800 2100);
FORCEPROP 2 LAST $XR0 146 
J 0
(13989 2100);
DISPLAY 0.638298 (13989 2100);
PAINT MONO (13989 2100);
FORCEPROP 2 LAST $XR1 191 
J 0
(13989 2100);
DISPLAY 0.638298 (13989 2100);
PAINT MONO (13989 2100);
FORCEPROP 2 LAST CDS_LIB mstr_standard
J 0
(13800 2100);
PAINT ORANGE (13800 2100);
DISPLAY INVISIBLE (13800 2100);
FORCEPROP 1 LAST OFFPAGE TRUE
J 0
(14125 1975);
DISPLAY 1.170213 (14125 1975);
PAINT GREEN (14125 1975);
DISPLAY INVISIBLE (14125 1975);
FORCEPROP 1 LAST COMMENT_BODY TRUE
J 0
(13755 2005);
DISPLAY 1.170213 (13755 2005);
PAINT GREEN (13755 2005);
DISPLAY INVISIBLE (13755 2005);
FORCEPROP 2 LAST PATH I163
J 0
(13975 2175);
DISPLAY 1.021277 (13975 2175);
PAINT ORANGE (13975 2175);
DISPLAY INVISIBLE (13975 2175);
FORCEADD OFFPAGE..2
(13800 2050);
FORCEPROP 2 LAST $XR0 151 
J 0
(13989 2050);
DISPLAY 0.638298 (13989 2050);
PAINT MONO (13989 2050);
FORCEPROP 2 LAST $XR2 191 
J 0
(13989 2050);
DISPLAY 0.638298 (13989 2050);
PAINT MONO (13989 2050);
FORCEPROP 2 LAST $XR1 146 
J 0
(13989 2050);
DISPLAY 0.638298 (13989 2050);
PAINT MONO (13989 2050);
FORCEPROP 2 LAST CDS_LIB mstr_standard
J 0
(13800 2050);
PAINT ORANGE (13800 2050);
DISPLAY INVISIBLE (13800 2050);
FORCEPROP 1 LAST OFFPAGE TRUE
J 0
(14125 1925);
DISPLAY 1.170213 (14125 1925);
PAINT GREEN (14125 1925);
DISPLAY INVISIBLE (14125 1925);
FORCEPROP 1 LAST COMMENT_BODY TRUE
J 0
(13755 1955);
DISPLAY 1.170213 (13755 1955);
PAINT GREEN (13755 1955);
DISPLAY INVISIBLE (13755 1955);
FORCEPROP 2 LAST PATH I164
J 0
(13975 2125);
DISPLAY 1.021277 (13975 2125);
PAINT ORANGE (13975 2125);
DISPLAY INVISIBLE (13975 2125);
FORCEADD OFFPAGE..2
(13800 1950);
FORCEPROP 2 LAST $XR0 190 
J 0
(13989 1950);
DISPLAY 0.638298 (13989 1950);
PAINT MONO (13989 1950);
FORCEPROP 2 LAST CDS_LIB mstr_standard
J 0
(13800 1950);
PAINT ORANGE (13800 1950);
DISPLAY INVISIBLE (13800 1950);
FORCEPROP 1 LAST OFFPAGE TRUE
J 0
(14125 1825);
DISPLAY 1.170213 (14125 1825);
PAINT GREEN (14125 1825);
DISPLAY INVISIBLE (14125 1825);
FORCEPROP 1 LAST COMMENT_BODY TRUE
J 0
(13755 1855);
DISPLAY 1.170213 (13755 1855);
PAINT GREEN (13755 1855);
DISPLAY INVISIBLE (13755 1855);
FORCEPROP 2 LAST PATH I165
J 0
(13975 2025);
DISPLAY 1.021277 (13975 2025);
PAINT ORANGE (13975 2025);
DISPLAY INVISIBLE (13975 2025);
FORCEADD OFFPAGE..2
(13800 1900);
FORCEPROP 2 LAST $XR0 113 
J 0
(13989 1900);
DISPLAY 0.638298 (13989 1900);
PAINT MONO (13989 1900);
FORCEPROP 2 LAST $XR1 190 
J 0
(14109 1900);
DISPLAY 0.638298 (14109 1900);
PAINT MONO (14109 1900);
FORCEPROP 2 LAST CDS_LIB mstr_standard
J 0
(13800 1900);
PAINT ORANGE (13800 1900);
DISPLAY INVISIBLE (13800 1900);
FORCEPROP 1 LAST OFFPAGE TRUE
J 0
(14125 1775);
DISPLAY 1.170213 (14125 1775);
PAINT GREEN (14125 1775);
DISPLAY INVISIBLE (14125 1775);
FORCEPROP 1 LAST COMMENT_BODY TRUE
J 0
(13755 1805);
DISPLAY 1.170213 (13755 1805);
PAINT GREEN (13755 1805);
DISPLAY INVISIBLE (13755 1805);
FORCEPROP 2 LAST PATH I166
J 0
(13975 1975);
DISPLAY 1.021277 (13975 1975);
PAINT ORANGE (13975 1975);
DISPLAY INVISIBLE (13975 1975);
FORCEADD OFFPAGE..2
(13800 1850);
FORCEPROP 2 LAST $XR0 190 
J 0
(13989 1850);
DISPLAY 0.638298 (13989 1850);
PAINT MONO (13989 1850);
FORCEPROP 2 LAST CDS_LIB mstr_standard
J 0
(13800 1850);
PAINT ORANGE (13800 1850);
DISPLAY INVISIBLE (13800 1850);
FORCEPROP 1 LAST OFFPAGE TRUE
J 0
(14125 1725);
DISPLAY 1.170213 (14125 1725);
PAINT GREEN (14125 1725);
DISPLAY INVISIBLE (14125 1725);
FORCEPROP 1 LAST COMMENT_BODY TRUE
J 0
(13755 1755);
DISPLAY 1.170213 (13755 1755);
PAINT GREEN (13755 1755);
DISPLAY INVISIBLE (13755 1755);
FORCEPROP 2 LAST PATH I167
J 0
(13975 1925);
DISPLAY 1.021277 (13975 1925);
PAINT ORANGE (13975 1925);
DISPLAY INVISIBLE (13975 1925);
FORCEADD P3V3_STBY..1
(13275 1325);
FORCEPROP 3 LASTPIN (13275 1275) SIG_NAME P3V3_STBY\g
J 0
(13285 1285);
DISPLAY 0.659574 (13285 1285);
PAINT MONO (13285 1285);
DISPLAY INVISIBLE (13285 1285);
FORCEPROP 1 LAST VOLTAGE 3.3V
J 0
(13230 1282);
DISPLAY 0.340426 (13230 1282);
PAINT SKYBLUE (13230 1282);
DISPLAY INVISIBLE (13230 1282);
FORCEPROP 1 LAST SIZE 1B
J 0
(13320 1347);
DISPLAY 0.340426 (13320 1347);
PAINT GREEN (13320 1347);
DISPLAY INVISIBLE (13320 1347);
FORCEPROP 2 LAST CDS_LIB mstr_symbols
J 0
(13275 1325);
PAINT ORANGE (13275 1325);
DISPLAY INVISIBLE (13275 1325);
FORCEPROP 1 LAST BODY_TYPE PLUMBING
J 0
(13230 1282);
DISPLAY 0.340426 (13230 1282);
PAINT GREEN (13230 1282);
DISPLAY INVISIBLE (13230 1282);
FORCEPROP 1 LAST PATH I169
J 0
(13320 1327);
DISPLAY 0.340426 (13320 1327);
PAINT GREEN (13320 1327);
DISPLAY INVISIBLE (13320 1327);
FORCEPROP 1 LAST HDL_POWER P3V3_STBY
J 0
(12975 1200);
DISPLAY 0.872340 (12975 1200);
PAINT GREEN (12975 1200);
DISPLAY INVISIBLE (12975 1200);
FORCEADD OFFPAGE..3
(13725 3500);
FORCEPROP 2 LAST $XR0 193 
J 0
(13939 3500);
DISPLAY 0.638298 (13939 3500);
PAINT MONO (13939 3500);
FORCEPROP 2 LAST $XR1 206 
J 0
(14059 3500);
DISPLAY 0.638298 (14059 3500);
PAINT MONO (14059 3500);
FORCEPROP 2 LAST $XR2 213 
J 0
(14179 3500);
DISPLAY 0.638298 (14179 3500);
PAINT MONO (14179 3500);
FORCEPROP 2 LAST CDS_LIB mstr_standard
J 0
(13725 3500);
PAINT MONO (13725 3500);
DISPLAY INVISIBLE (13725 3500);
FORCEPROP 1 LAST OFFPAGE TRUE
J 0
(14050 3375);
DISPLAY 1.170213 (14050 3375);
PAINT GREEN (14050 3375);
DISPLAY INVISIBLE (14050 3375);
FORCEPROP 1 LAST COMMENT_BODY TRUE
J 0
(13675 3400);
DISPLAY 1.170213 (13675 3400);
PAINT GREEN (13675 3400);
DISPLAY INVISIBLE (13675 3400);
FORCEPROP 2 LAST PATH I17
J 0
(13925 3575);
DISPLAY 1.021277 (13925 3575);
PAINT ORANGE (13925 3575);
DISPLAY INVISIBLE (13925 3575);
FORCEADD RES..1
(11800 3900);
FORCEPROP 1 LAST LOCATION R7P25
J 0
(11725 3950);
DISPLAY 0.617021 (11725 3950);
PAINT AQUA (11725 3950);
FORCEPROP 1 LAST PART_NUMBER G21796-047
J 0
(12200 3750);
DISPLAY 0.617021 (12200 3750);
PAINT BLUE (12200 3750);
FORCEPROP 1 LAST VALUE 49.9
J 2
(11400 3800);
DISPLAY 0.617021 (11400 3800);
PAINT SKYBLUE (11400 3800);
FORCEPROP 1 LAST TOLERANCE 1%
J 0
(11425 3800);
DISPLAY 0.617021 (11425 3800);
PAINT SKYBLUE (11425 3800);
FORCEPROP 1 LAST PACK_TYPE 0402
J 0
(11725 3775);
DISPLAY 0.617021 (11725 3775);
PAINT SKYBLUE (11725 3775);
FORCEPROP 1 LAST MATERIAL CHIP
J 0
(11500 3800);
DISPLAY 0.617021 (11500 3800);
PAINT SKYBLUE (11500 3800);
FORCEPROP 1 LAST WATTAGE 1/16W
J 2
(11300 3800);
DISPLAY 0.617021 (11300 3800);
PAINT SKYBLUE (11300 3800);
FORCEPROP 1 LASTPIN (11900 3900) $PN 2
J 0
(11862 3912);
DISPLAY 0.617021 (11862 3912);
PAINT ORANGE (11862 3912);
FORCEPROP 1 LASTPIN (11700 3900) $PN 1
J 0
(11712 3912);
DISPLAY 0.617021 (11712 3912);
PAINT ORANGE (11712 3912);
FORCEPROP 2 LAST SEC_TYPE 0402
J 0
(11750 4100);
DISPLAY 1.021277 (11750 4100);
PAINT ORANGE (11750 4100);
DISPLAY INVISIBLE (11750 4100);
FORCEPROP 2 LAST CDS_LIB mstr_discrete
J 0
(11800 3900);
PAINT ORANGE (11800 3900);
DISPLAY INVISIBLE (11800 3900);
FORCEPROP 2 LAST BOM_COST PROC_SOCKET
J 0
(11775 4025);
PAINT MONO (11775 4025);
DISPLAY INVISIBLE (11775 4025);
FORCEPROP 2 LAST SEC 1
J 0
(11750 4100);
DISPLAY 0.680851 (11750 4100);
PAINT MONO (11750 4100);
DISPLAY INVISIBLE (11750 4100);
FORCEPROP 2 LAST CDS_LOCATION R7P25
J 0
(11725 3950);
DISPLAY 0.617021 (11725 3950);
PAINT AQUA (11725 3950);
DISPLAY INVISIBLE (11725 3950);
FORCEPROP 1 LAST PATH I170
J 0
(11750 4050);
DISPLAY 0.978723 (11750 4050);
PAINT WHITE (11750 4050);
DISPLAY INVISIBLE (11750 4050);
FORCEPROP 2 LAST ROOM CPU1
J 0
(11775 3975);
PAINT MONO (11775 3975);
DISPLAY INVISIBLE (11775 3975);
FORCEADD SKX_EXT_B..1
(10225 2500);
FORCEPROP 1 LAST LOCATION U2D1
J 0
(9325 4400);
DISPLAY 0.617021 (9325 4400);
PAINT AQUA (9325 4400);
FORCEPROP 1 LAST PART_NUMBER TBD
J 0
(9325 600);
DISPLAY 0.617021 (9325 600);
PAINT BLUE (9325 600);
FORCEPROP 1 LAST MATERIAL IC
J 0
(9325 4350);
DISPLAY 0.617021 (9325 4350);
PAINT SKYBLUE (9325 4350);
FORCEPROP 2 LASTPIN (9275 1700) $PN CK29
J 2
(9265 1710);
DISPLAY 0.617021 (9265 1710);
PAINT ORANGE (9265 1710);
FORCEPROP 2 LASTPIN (9275 1650) $PN CL28
J 2
(9265 1660);
DISPLAY 0.617021 (9265 1660);
PAINT ORANGE (9265 1660);
FORCEPROP 2 LASTPIN (9275 1800) $PN AP29
J 2
(9265 1810);
DISPLAY 0.617021 (9265 1810);
PAINT ORANGE (9265 1810);
FORCEPROP 2 LASTPIN (9275 1750) $PN AT29
J 2
(9265 1760);
DISPLAY 0.617021 (9265 1760);
PAINT ORANGE (9265 1760);
FORCEPROP 2 LASTPIN (11175 2500) $PN AV15
J 0
(11185 2510);
DISPLAY 0.617021 (11185 2510);
PAINT ORANGE (11185 2510);
FORCEPROP 2 LASTPIN (11175 2550) $PN AW18
J 0
(11185 2560);
DISPLAY 0.617021 (11185 2560);
PAINT ORANGE (11185 2560);
FORCEPROP 2 LASTPIN (11175 1750) $PN AM11
J 0
(11185 1760);
DISPLAY 0.617021 (11185 1760);
PAINT ORANGE (11185 1760);
FORCEPROP 2 LASTPIN (9275 850) $PN Y13
J 2
(9265 860);
DISPLAY 0.617021 (9265 860);
PAINT ORANGE (9265 860);
FORCEPROP 2 LASTPIN (9275 900) $PN W14
J 2
(9265 910);
DISPLAY 0.617021 (9265 910);
PAINT ORANGE (9265 910);
FORCEPROP 2 LASTPIN (11175 2800) $PN AB15
J 0
(11185 2810);
DISPLAY 0.617021 (11185 2810);
PAINT ORANGE (11185 2810);
FORCEPROP 2 LASTPIN (11175 1300) $PN AW14
J 0
(11185 1310);
DISPLAY 0.617021 (11185 1310);
PAINT ORANGE (11185 1310);
FORCEPROP 2 LASTPIN (11175 1250) $PN DC50
J 0
(11185 1260);
DISPLAY 0.617021 (11185 1260);
PAINT ORANGE (11185 1260);
FORCEPROP 2 LASTPIN (11175 1200) $PN DB51
J 0
(11185 1210);
DISPLAY 0.617021 (11185 1210);
PAINT ORANGE (11185 1210);
FORCEPROP 2 LASTPIN (11175 1150) $PN AY19
J 0
(11185 1160);
DISPLAY 0.617021 (11185 1160);
PAINT ORANGE (11185 1160);
FORCEPROP 2 LASTPIN (11175 800) $PN AE14
J 0
(11185 810);
DISPLAY 0.617021 (11185 810);
PAINT ORANGE (11185 810);
FORCEPROP 2 LASTPIN (9275 1000) $PN AC14
J 2
(9265 1010);
DISPLAY 0.617021 (9265 1010);
PAINT ORANGE (9265 1010);
FORCEPROP 2 LASTPIN (9275 950) $PN AA14
J 2
(9265 960);
DISPLAY 0.617021 (9265 960);
PAINT ORANGE (9265 960);
FORCEPROP 2 LASTPIN (11175 3650) $PN DJ44
J 0
(11185 3660);
DISPLAY 0.617021 (11185 3660);
PAINT ORANGE (11185 3660);
FORCEPROP 2 LASTPIN (11175 3500) $PN DB45
J 0
(11185 3510);
DISPLAY 0.617021 (11185 3510);
PAINT ORANGE (11185 3510);
FORCEPROP 2 LASTPIN (11175 3600) $PN DG44
J 0
(11185 3610);
DISPLAY 0.617021 (11185 3610);
PAINT ORANGE (11185 3610);
FORCEPROP 2 LASTPIN (11175 3450) $PN DC44
J 0
(11185 3460);
DISPLAY 0.617021 (11185 3460);
PAINT ORANGE (11185 3460);
FORCEPROP 2 LASTPIN (11175 3550) $PN DL44
J 0
(11185 3560);
DISPLAY 0.617021 (11185 3560);
PAINT ORANGE (11185 3560);
FORCEPROP 2 LASTPIN (11175 3400) $PN DE44
J 0
(11185 3410);
DISPLAY 0.617021 (11185 3410);
PAINT ORANGE (11185 3410);
FORCEPROP 2 LASTPIN (11175 2200) $PN AU20
J 0
(11185 2210);
DISPLAY 0.617021 (11185 2210);
PAINT ORANGE (11185 2210);
FORCEPROP 2 LASTPIN (11175 2300) $PN AU16
J 0
(11185 2310);
DISPLAY 0.617021 (11185 2310);
PAINT ORANGE (11185 2310);
FORCEPROP 2 LASTPIN (11175 2250) $PN AU22
J 0
(11185 2260);
DISPLAY 0.617021 (11185 2260);
PAINT ORANGE (11185 2260);
FORCEPROP 2 LASTPIN (9275 2100) $PN CW58
J 2
(9265 2110);
DISPLAY 0.617021 (9265 2110);
PAINT ORANGE (9265 2110);
FORCEPROP 2 LASTPIN (9275 2150) $PN CT59
J 2
(9265 2160);
DISPLAY 0.617021 (9265 2160);
PAINT ORANGE (9265 2160);
FORCEPROP 2 LASTPIN (11175 1700) $PN CV59
J 0
(11185 1710);
DISPLAY 0.617021 (11185 1710);
PAINT ORANGE (11185 1710);
FORCEPROP 2 LASTPIN (11175 900) $PN AB13
J 0
(11185 910);
DISPLAY 0.617021 (11185 910);
PAINT ORANGE (11185 910);
FORCEPROP 2 LASTPIN (11175 2700) $PN AR18
J 0
(11185 2710);
DISPLAY 0.617021 (11185 2710);
PAINT ORANGE (11185 2710);
FORCEPROP 2 LASTPIN (11175 4100) $PN AP21
J 0
(11185 4110);
DISPLAY 0.617021 (11185 4110);
PAINT ORANGE (11185 4110);
FORCEPROP 2 LASTPIN (11175 4150) $PN BC24
J 0
(11185 4160);
DISPLAY 0.617021 (11185 4160);
PAINT ORANGE (11185 4160);
FORCEPROP 2 LASTPIN (11175 2850) $PN AC16
J 0
(11185 2860);
DISPLAY 0.617021 (11185 2860);
PAINT ORANGE (11185 2860);
FORCEPROP 2 LASTPIN (11175 2900) $PN AB17
J 0
(11185 2910);
DISPLAY 0.617021 (11185 2910);
PAINT ORANGE (11185 2910);
FORCEPROP 2 LASTPIN (11175 2100) $PN DB71
J 0
(11185 2110);
DISPLAY 0.617021 (11185 2110);
PAINT ORANGE (11185 2110);
FORCEPROP 2 LASTPIN (11175 2050) $PN CY71
J 0
(11185 2060);
DISPLAY 0.617021 (11185 2060);
PAINT ORANGE (11185 2060);
FORCEPROP 2 LASTPIN (11175 1050) $PN AR12
J 0
(11185 1060);
DISPLAY 0.617021 (11185 1060);
PAINT ORANGE (11185 1060);
FORCEPROP 2 LASTPIN (11175 1000) $PN AG16
J 0
(11185 1010);
DISPLAY 0.617021 (11185 1010);
PAINT ORANGE (11185 1010);
FORCEPROP 2 LASTPIN (11175 3850) $PN AT19
J 0
(11185 3860);
DISPLAY 0.617021 (11185 3860);
PAINT ORANGE (11185 3860);
FORCEPROP 2 LASTPIN (11175 3900) $PN AR14
J 0
(11185 3910);
DISPLAY 0.617021 (11185 3910);
PAINT ORANGE (11185 3910);
FORCEPROP 2 LASTPIN (11175 2400) $PN AF15
J 0
(11185 2410);
DISPLAY 0.617021 (11185 2410);
PAINT ORANGE (11185 2410);
FORCEPROP 2 LASTPIN (11175 1950) $PN DA72
J 0
(11185 1960);
DISPLAY 0.617021 (11185 1960);
PAINT ORANGE (11185 1960);
FORCEPROP 2 LASTPIN (11175 1900) $PN CW72
J 0
(11185 1910);
DISPLAY 0.617021 (11185 1910);
PAINT ORANGE (11185 1910);
FORCEPROP 2 LASTPIN (11175 1850) $PN DC72
J 0
(11185 1860);
DISPLAY 0.617021 (11185 1860);
PAINT ORANGE (11185 1860);
FORCEPROP 2 LASTPIN (11175 1450) $PN CW56
J 0
(11185 1460);
DISPLAY 0.617021 (11185 1460);
PAINT ORANGE (11185 1460);
FORCEPROP 2 LASTPIN (11175 1400) $PN CV57
J 0
(11185 1410);
DISPLAY 0.617021 (11185 1410);
PAINT ORANGE (11185 1410);
FORCEPROP 2 LASTPIN (11175 1350) $PN CU58
J 0
(11185 1360);
DISPLAY 0.617021 (11185 1360);
PAINT ORANGE (11185 1360);
FORCEPROP 2 LASTPIN (11175 3750) $PN AU12
J 0
(11185 3760);
DISPLAY 0.617021 (11185 3760);
PAINT ORANGE (11185 3760);
FORCEPROP 2 LASTPIN (9275 2250) $PN AL18
J 2
(9265 2260);
DISPLAY 0.617021 (9265 2260);
PAINT ORANGE (9265 2260);
FORCEPROP 2 LASTPIN (9275 2300) $PN AM19
J 2
(9265 2310);
DISPLAY 0.617021 (9265 2310);
PAINT ORANGE (9265 2310);
FORCEPROP 2 LASTPIN (9275 1900) $PN CL30
J 2
(9265 1910);
DISPLAY 0.617021 (9265 1910);
PAINT ORANGE (9265 1910);
FORCEPROP 2 LASTPIN (9275 1850) $PN CN30
J 2
(9265 1860);
DISPLAY 0.617021 (9265 1860);
PAINT ORANGE (9265 1860);
FORCEPROP 2 LASTPIN (9275 2000) $PN CR30
J 2
(9265 2010);
DISPLAY 0.617021 (9265 2010);
PAINT ORANGE (9265 2010);
FORCEPROP 2 LASTPIN (9275 1950) $PN CP29
J 2
(9265 1960);
DISPLAY 0.617021 (9265 1960);
PAINT ORANGE (9265 1960);
FORCEPROP 2 LASTPIN (11175 1600) $PN AP11
J 0
(11185 1610);
DISPLAY 0.617021 (11185 1610);
PAINT ORANGE (11185 1610);
FORCEPROP 2 LASTPIN (11175 3000) $PN AN20
J 0
(11185 3010);
DISPLAY 0.617021 (11185 3010);
PAINT ORANGE (11185 3010);
FORCEPROP 2 LASTPIN (9275 3350) $PN AF13
J 2
(9265 3360);
DISPLAY 0.617021 (9265 3360);
PAINT ORANGE (9265 3360);
FORCEPROP 2 LASTPIN (9275 3400) $PN AH13
J 2
(9265 3410);
DISPLAY 0.617021 (9265 3410);
PAINT ORANGE (9265 3410);
FORCEPROP 2 LASTPIN (9275 1600) $PN CT31
J 2
(9265 1610);
DISPLAY 0.617021 (9265 1610);
PAINT ORANGE (9265 1610);
FORCEPROP 2 LASTPIN (9275 1550) $PN CU32
J 2
(9265 1560);
DISPLAY 0.617021 (9265 1560);
PAINT ORANGE (9265 1560);
FORCEPROP 2 LASTPIN (11175 1550) $PN AE20
J 0
(11185 1560);
DISPLAY 0.617021 (11185 1560);
PAINT ORANGE (11185 1560);
FORCEPROP 2 LASTPIN (11175 2650) $PN AV17
J 0
(11185 2660);
DISPLAY 0.617021 (11185 2660);
PAINT ORANGE (11185 2660);
FORCEPROP 2 LASTPIN (11175 3200) $PN AL12
J 0
(11185 3210);
DISPLAY 0.617021 (11185 3210);
PAINT ORANGE (11185 3210);
FORCEPROP 2 LASTPIN (11175 3150) $PN AK11
J 0
(11185 3160);
DISPLAY 0.617021 (11185 3160);
PAINT ORANGE (11185 3160);
FORCEPROP 2 LASTPIN (11175 3100) $PN AJ12
J 0
(11185 3110);
DISPLAY 0.617021 (11185 3110);
PAINT ORANGE (11185 3110);
FORCEPROP 2 LASTPIN (11175 4000) $PN AJ14
J 0
(11185 4010);
DISPLAY 0.617021 (11185 4010);
PAINT ORANGE (11185 4010);
FORCEPROP 2 LASTPIN (9275 2550) $PN AD17
J 2
(9265 2560);
DISPLAY 0.617021 (9265 2560);
PAINT ORANGE (9265 2560);
FORCEPROP 2 LASTPIN (9275 2450) $PN AE18
J 2
(9265 2460);
DISPLAY 0.617021 (9265 2460);
PAINT ORANGE (9265 2460);
FORCEPROP 2 LASTPIN (9275 3500) $PN DV63
J 2
(9265 3510);
DISPLAY 0.617021 (9265 3510);
PAINT ORANGE (9265 3510);
FORCEPROP 2 LASTPIN (9275 2750) $PN DD49
J 2
(9265 2760);
DISPLAY 0.617021 (9265 2760);
PAINT ORANGE (9265 2760);
FORCEPROP 2 LASTPIN (9275 2700) $PN DD47
J 2
(9265 2710);
DISPLAY 0.617021 (9265 2710);
PAINT ORANGE (9265 2710);
FORCEPROP 2 LASTPIN (9275 2650) $PN DC48
J 2
(9265 2660);
DISPLAY 0.617021 (9265 2660);
PAINT ORANGE (9265 2660);
FORCEPROP 2 LASTPIN (9275 3650) $PN CR28
J 2
(9265 3660);
DISPLAY 0.617021 (9265 3660);
PAINT ORANGE (9265 3660);
FORCEPROP 2 LASTPIN (9275 2500) $PN AF17
J 2
(9265 2510);
DISPLAY 0.617021 (9265 2510);
PAINT ORANGE (9265 2510);
FORCEPROP 2 LASTPIN (9275 2400) $PN AJ18
J 2
(9265 2410);
DISPLAY 0.617021 (9265 2410);
PAINT ORANGE (9265 2410);
FORCEPROP 2 LASTPIN (9275 3550) $PN U64
J 2
(9265 3560);
DISPLAY 0.617021 (9265 3560);
PAINT ORANGE (9265 3560);
FORCEPROP 2 LASTPIN (9275 2900) $PN AC42
J 2
(9265 2910);
DISPLAY 0.617021 (9265 2910);
PAINT ORANGE (9265 2910);
FORCEPROP 2 LASTPIN (9275 2850) $PN AB43
J 2
(9265 2860);
DISPLAY 0.617021 (9265 2860);
PAINT ORANGE (9265 2860);
FORCEPROP 2 LASTPIN (9275 2800) $PN Y43
J 2
(9265 2810);
DISPLAY 0.617021 (9265 2810);
PAINT ORANGE (9265 2810);
FORCEPROP 2 LASTPIN (9275 3700) $PN AN30
J 2
(9265 3710);
DISPLAY 0.617021 (9265 3710);
PAINT ORANGE (9265 3710);
FORCEPROP 2 LASTPIN (9275 3250) $PN CV61
J 2
(9265 3260);
DISPLAY 0.617021 (9265 3260);
PAINT ORANGE (9265 3260);
FORCEPROP 2 LASTPIN (9275 3200) $PN CT61
J 2
(9265 3210);
DISPLAY 0.617021 (9265 3210);
PAINT ORANGE (9265 3210);
FORCEPROP 2 LASTPIN (9275 3150) $PN CP61
J 2
(9265 3160);
DISPLAY 0.617021 (9265 3160);
PAINT ORANGE (9265 3160);
FORCEPROP 2 LASTPIN (9275 3100) $PN AH63
J 2
(9265 3110);
DISPLAY 0.617021 (9265 3110);
PAINT ORANGE (9265 3110);
FORCEPROP 2 LASTPIN (9275 3050) $PN AK63
J 2
(9265 3060);
DISPLAY 0.617021 (9265 3060);
PAINT ORANGE (9265 3060);
FORCEPROP 2 LASTPIN (9275 3000) $PN AJ64
J 2
(9265 3010);
DISPLAY 0.617021 (9265 3010);
PAINT ORANGE (9265 3010);
FORCEPROP 2 LASTPIN (11175 3300) $PN AL14
J 0
(11185 3310);
DISPLAY 0.617021 (11185 3310);
PAINT ORANGE (11185 3310);
FORCEPROP 2 LASTPIN (9275 1450) $PN AC12
J 2
(9265 1460);
DISPLAY 0.617021 (9265 1460);
PAINT ORANGE (9265 1460);
FORCEPROP 2 LASTPIN (9275 1400) $PN AE12
J 2
(9265 1410);
DISPLAY 0.617021 (9265 1410);
PAINT ORANGE (9265 1410);
FORCEPROP 2 LASTPIN (9275 1350) $PN Y11
J 2
(9265 1360);
DISPLAY 0.617021 (9265 1360);
PAINT ORANGE (9265 1360);
FORCEPROP 2 LASTPIN (9275 1300) $PN AA12
J 2
(9265 1310);
DISPLAY 0.617021 (9265 1310);
PAINT ORANGE (9265 1310);
FORCEPROP 2 LASTPIN (9275 1250) $PN AF11
J 2
(9265 1260);
DISPLAY 0.617021 (9265 1260);
PAINT ORANGE (9265 1260);
FORCEPROP 2 LASTPIN (9275 1200) $PN AG10
J 2
(9265 1210);
DISPLAY 0.617021 (9265 1210);
PAINT ORANGE (9265 1210);
FORCEPROP 2 LASTPIN (9275 1150) $PN AH11
J 2
(9265 1160);
DISPLAY 0.617021 (9265 1160);
PAINT ORANGE (9265 1160);
FORCEPROP 2 LASTPIN (9275 1100) $PN AJ10
J 2
(9265 1110);
DISPLAY 0.617021 (9265 1110);
PAINT ORANGE (9265 1110);
FORCEPROP 2 LASTPIN (11175 2600) $PN BD23
J 0
(11185 2610);
DISPLAY 0.617021 (11185 2610);
PAINT ORANGE (11185 2610);
FORCEPROP 2 LASTPIN (11175 2450) $PN BA20
J 0
(11185 2460);
DISPLAY 0.617021 (11185 2460);
PAINT ORANGE (11185 2460);
FORCEPROP 2 LASTPIN (9275 3850) $PN CU26
J 2
(9265 3860);
DISPLAY 0.617021 (9265 3860);
PAINT ORANGE (9265 3860);
FORCEPROP 2 LASTPIN (9275 3800) $PN CT25
J 2
(9265 3810);
DISPLAY 0.617021 (9265 3810);
PAINT ORANGE (9265 3810);
FORCEPROP 2 LASTPIN (9275 4000) $PN CP27
J 2
(9265 4010);
DISPLAY 0.617021 (9265 4010);
PAINT ORANGE (9265 4010);
FORCEPROP 2 LASTPIN (9275 3950) $PN CR26
J 2
(9265 3960);
DISPLAY 0.617021 (9265 3960);
PAINT ORANGE (9265 3960);
FORCEPROP 2 LASTPIN (9275 4150) $PN AW24
J 2
(9265 4160);
DISPLAY 0.617021 (9265 4160);
PAINT ORANGE (9265 4160);
FORCEPROP 2 LASTPIN (9275 4100) $PN AU24
J 2
(9265 4110);
DISPLAY 0.617021 (9265 4110);
PAINT ORANGE (9265 4110);
FORCEPROP 1 LAST PACK_TYPE BGA1
J 0
(9325 4450);
PAINT SKYBLUE (9325 4450);
DISPLAY INVISIBLE (9325 4450);
FORCEPROP 2 LAST SEC_TYPE BGA1
J 0
(9325 4450);
DISPLAY 1.021277 (9325 4450);
PAINT ORANGE (9325 4450);
DISPLAY INVISIBLE (9325 4450);
FORCEPROP 2 LAST CDS_LIB chpset_lib
J 0
(10225 2500);
PAINT ORANGE (10225 2500);
DISPLAY INVISIBLE (10225 2500);
FORCEPROP 2 LAST SEC 1
J 0
(9325 4450);
DISPLAY 0.680851 (9325 4450);
PAINT MONO (9325 4450);
DISPLAY INVISIBLE (9325 4450);
FORCEPROP 2 LAST CDS_LOCATION U2D1
J 0
(9325 4400);
DISPLAY 0.617021 (9325 4400);
PAINT AQUA (9325 4400);
DISPLAY INVISIBLE (9325 4400);
FORCEPROP 1 LAST PATH I172
J 0
(10225 4350);
PAINT GREEN (10225 4350);
DISPLAY INVISIBLE (10225 4350);
FORCEPROP 0 LAST ROOM CPU1
J 0
(9325 4500);
DISPLAY 1.021277 (9325 4500);
PAINT ORANGE (9325 4500);
DISPLAY INVISIBLE (9325 4500);
FORCEADD OFFPAGE..5
(8225 2300);
FORCEPROP 2 LAST $XR0 163 
J 0
(7970 2300);
DISPLAY 0.638298 (7970 2300);
PAINT MONO (7970 2300);
FORCEPROP 2 LAST CDS_LIB mstr_standard
J 0
(8225 2300);
PAINT MONO (8225 2300);
DISPLAY INVISIBLE (8225 2300);
FORCEPROP 1 LAST OFFPAGE TRUE
J 0
(8550 2175);
DISPLAY 1.170213 (8550 2175);
PAINT GREEN (8550 2175);
DISPLAY INVISIBLE (8550 2175);
FORCEPROP 1 LAST COMMENT_BODY TRUE
J 0
(8325 2225);
DISPLAY 1.170213 (8325 2225);
PAINT GREEN (8325 2225);
DISPLAY INVISIBLE (8325 2225);
FORCEPROP 2 LAST PATH I173
J 0
(8275 2375);
DISPLAY 1.021277 (8275 2375);
PAINT ORANGE (8275 2375);
DISPLAY INVISIBLE (8275 2375);
FORCEADD OFFPAGE..6
(8250 2250);
FORCEPROP 2 LAST $XR0 163 
J 0
(7970 2250);
DISPLAY 0.638298 (7970 2250);
PAINT MONO (7970 2250);
FORCEPROP 2 LAST CDS_LIB mstr_standard
J 0
(8250 2250);
PAINT MONO (8250 2250);
DISPLAY INVISIBLE (8250 2250);
FORCEPROP 1 LAST OFFPAGE TRUE
J 0
(8575 2125);
DISPLAY 1.170213 (8575 2125);
PAINT GREEN (8575 2125);
DISPLAY INVISIBLE (8575 2125);
FORCEPROP 1 LAST COMMENT_BODY TRUE
J 0
(8350 2175);
DISPLAY 1.170213 (8350 2175);
PAINT GREEN (8350 2175);
DISPLAY INVISIBLE (8350 2175);
FORCEPROP 2 LAST PATH I174
J 0
(8300 2325);
DISPLAY 1.021277 (8300 2325);
PAINT ORANGE (8300 2325);
DISPLAY INVISIBLE (8300 2325);
FORCEADD OFFPAGE..4
(12525 1300);
FORCEPROP 2 LAST $XR0 90 
J 0
(12711 1300);
DISPLAY 0.638298 (12711 1300);
PAINT MONO (12711 1300);
FORCEPROP 2 LAST CDS_LIB mstr_standard
J 0
(12525 1300);
PAINT MONO (12525 1300);
DISPLAY INVISIBLE (12525 1300);
FORCEPROP 1 LAST OFFPAGE TRUE
J 0
(12850 1175);
DISPLAY 1.170213 (12850 1175);
PAINT GREEN (12850 1175);
DISPLAY INVISIBLE (12850 1175);
FORCEPROP 1 LAST COMMENT_BODY TRUE
J 0
(12500 1200);
DISPLAY 1.170213 (12500 1200);
PAINT GREEN (12500 1200);
DISPLAY INVISIBLE (12500 1200);
FORCEPROP 2 LAST PATH I175
J 0
(12700 1375);
DISPLAY 1.021277 (12700 1375);
PAINT ORANGE (12700 1375);
DISPLAY INVISIBLE (12700 1375);
FORCEADD OFFPAGE..4
(12525 1250);
FORCEPROP 2 LAST $XR0 90 
J 0
(12711 1250);
DISPLAY 0.638298 (12711 1250);
PAINT MONO (12711 1250);
FORCEPROP 2 LAST CDS_LIB mstr_standard
J 0
(12525 1250);
PAINT ORANGE (12525 1250);
DISPLAY INVISIBLE (12525 1250);
FORCEPROP 1 LAST OFFPAGE TRUE
J 0
(12850 1125);
DISPLAY 1.170213 (12850 1125);
PAINT GREEN (12850 1125);
DISPLAY INVISIBLE (12850 1125);
FORCEPROP 1 LAST COMMENT_BODY TRUE
J 0
(12500 1150);
DISPLAY 1.170213 (12500 1150);
PAINT GREEN (12500 1150);
DISPLAY INVISIBLE (12500 1150);
FORCEPROP 2 LAST PATH I178
J 0
(12700 1325);
DISPLAY 1.021277 (12700 1325);
PAINT ORANGE (12700 1325);
DISPLAY INVISIBLE (12700 1325);
FORCEADD OFFPAGE..4
(12525 1200);
FORCEPROP 2 LAST $XR0 90 
J 0
(12711 1200);
DISPLAY 0.638298 (12711 1200);
PAINT MONO (12711 1200);
FORCEPROP 2 LAST CDS_LIB mstr_standard
J 0
(12525 1200);
PAINT ORANGE (12525 1200);
DISPLAY INVISIBLE (12525 1200);
FORCEPROP 1 LAST OFFPAGE TRUE
J 0
(12850 1075);
DISPLAY 1.170213 (12850 1075);
PAINT GREEN (12850 1075);
DISPLAY INVISIBLE (12850 1075);
FORCEPROP 1 LAST COMMENT_BODY TRUE
J 0
(12500 1100);
DISPLAY 1.170213 (12500 1100);
PAINT GREEN (12500 1100);
DISPLAY INVISIBLE (12500 1100);
FORCEPROP 2 LAST PATH I179
J 0
(12700 1275);
DISPLAY 1.021277 (12700 1275);
PAINT ORANGE (12700 1275);
DISPLAY INVISIBLE (12700 1275);
FORCEADD OFFPAGE..4
(13750 3400);
FORCEPROP 2 LAST $XR0 193 
J 0
(13936 3400);
DISPLAY 0.638298 (13936 3400);
PAINT MONO (13936 3400);
FORCEPROP 2 LAST $XR1 206 
J 0
(14056 3400);
DISPLAY 0.638298 (14056 3400);
PAINT MONO (14056 3400);
FORCEPROP 2 LAST $XR2 213 
J 0
(14176 3400);
DISPLAY 0.638298 (14176 3400);
PAINT MONO (14176 3400);
FORCEPROP 2 LAST CDS_LIB mstr_standard
J 0
(13750 3400);
PAINT MONO (13750 3400);
DISPLAY INVISIBLE (13750 3400);
FORCEPROP 1 LAST OFFPAGE TRUE
J 0
(14075 3275);
DISPLAY 1.170213 (14075 3275);
PAINT GREEN (14075 3275);
DISPLAY INVISIBLE (14075 3275);
FORCEPROP 1 LAST COMMENT_BODY TRUE
J 0
(13725 3300);
DISPLAY 1.170213 (13725 3300);
PAINT GREEN (13725 3300);
DISPLAY INVISIBLE (13725 3300);
FORCEPROP 2 LAST PATH I18
J 0
(13925 3475);
DISPLAY 1.021277 (13925 3475);
PAINT ORANGE (13925 3475);
DISPLAY INVISIBLE (13925 3475);
FORCEADD OFFPAGE..4
(12525 1150);
FORCEPROP 2 LAST $XR0 90 
J 0
(12711 1150);
DISPLAY 0.638298 (12711 1150);
PAINT MONO (12711 1150);
FORCEPROP 2 LAST CDS_LIB mstr_standard
J 0
(12525 1150);
PAINT ORANGE (12525 1150);
DISPLAY INVISIBLE (12525 1150);
FORCEPROP 1 LAST OFFPAGE TRUE
J 0
(12850 1025);
DISPLAY 1.170213 (12850 1025);
PAINT GREEN (12850 1025);
DISPLAY INVISIBLE (12850 1025);
FORCEPROP 1 LAST COMMENT_BODY TRUE
J 0
(12500 1050);
DISPLAY 1.170213 (12500 1050);
PAINT GREEN (12500 1050);
DISPLAY INVISIBLE (12500 1050);
FORCEPROP 2 LAST PATH I180
J 0
(12700 1225);
DISPLAY 1.021277 (12700 1225);
PAINT ORANGE (12700 1225);
DISPLAY INVISIBLE (12700 1225);
FORCEADD RES..2
(13275 1100);
FORCEPROP 1 LAST LOCATION R6P39
J 0
(13320 1225);
DISPLAY 0.617021 (13320 1225);
PAINT AQUA (13320 1225);
FORCEPROP 1 LAST PART_NUMBER G21796-072
J 0
(13315 975);
DISPLAY 0.617021 (13315 975);
PAINT BLUE (13315 975);
FORCEPROP 1 LAST VALUE 4.75K
J 0
(13320 1175);
DISPLAY 0.617021 (13320 1175);
PAINT SKYBLUE (13320 1175);
FORCEPROP 1 LAST TOLERANCE 1%
J 0
(13320 1125);
DISPLAY 0.617021 (13320 1125);
PAINT SKYBLUE (13320 1125);
FORCEPROP 1 LAST PACK_TYPE 0402
J 0
(13315 925);
DISPLAY 0.617021 (13315 925);
PAINT SKYBLUE (13315 925);
FORCEPROP 1 LAST MATERIAL CHIP
J 0
(13315 1025);
DISPLAY 0.617021 (13315 1025);
PAINT SKYBLUE (13315 1025);
FORCEPROP 1 LAST WATTAGE 1/16W
J 0
(13315 1075);
DISPLAY 0.617021 (13315 1075);
PAINT SKYBLUE (13315 1075);
FORCEPROP 1 LASTPIN (13275 1000) $PN 2
J 0
(13280 1010);
DISPLAY 0.617021 (13280 1010);
PAINT ORANGE (13280 1010);
FORCEPROP 1 LASTPIN (13275 1200) $PN 1
J 0
(13280 1162);
DISPLAY 0.617021 (13280 1162);
PAINT ORANGE (13280 1162);
FORCEPROP 2 LAST SEC_TYPE 0402
J 0
(13325 1325);
DISPLAY 1.021277 (13325 1325);
PAINT ORANGE (13325 1325);
DISPLAY INVISIBLE (13325 1325);
FORCEPROP 2 LAST CDS_LIB mstr_discrete
J 0
(13275 1100);
PAINT ORANGE (13275 1100);
DISPLAY INVISIBLE (13275 1100);
FORCEPROP 2 LAST SEC 1
J 0
(13325 1325);
DISPLAY 0.680851 (13325 1325);
PAINT MONO (13325 1325);
DISPLAY INVISIBLE (13325 1325);
FORCEPROP 2 LAST CDS_LOCATION R6P39
J 0
(13320 1225);
DISPLAY 0.617021 (13320 1225);
PAINT AQUA (13320 1225);
DISPLAY INVISIBLE (13320 1225);
FORCEPROP 1 LAST PATH I181
J 0
(13325 1275);
DISPLAY 0.978723 (13325 1275);
PAINT WHITE (13325 1275);
DISPLAY INVISIBLE (13325 1275);
FORCEPROP 0 LAST ROOM CPU1
J 0
(13325 1325);
DISPLAY 1.021277 (13325 1325);
PAINT ORANGE (13325 1325);
DISPLAY INVISIBLE (13325 1325);
FORCEADD OFFPAGE..6
(7975 1450);
FORCEPROP 2 LAST $XR0 21 
J 0
(7726 1450);
DISPLAY 0.638298 (7726 1450);
PAINT MONO (7726 1450);
FORCEPROP 2 LAST $XR1 112 
J 0
(7606 1450);
DISPLAY 0.638298 (7606 1450);
PAINT MONO (7606 1450);
FORCEPROP 2 LAST CDS_LIB mstr_standard
J 0
(7975 1450);
PAINT ORANGE (7975 1450);
DISPLAY INVISIBLE (7975 1450);
FORCEPROP 1 LAST OFFPAGE TRUE
J 0
(8300 1325);
DISPLAY 1.170213 (8300 1325);
PAINT GREEN (8300 1325);
DISPLAY INVISIBLE (8300 1325);
FORCEPROP 1 LAST COMMENT_BODY TRUE
J 0
(8075 1375);
DISPLAY 1.170213 (8075 1375);
PAINT GREEN (8075 1375);
DISPLAY INVISIBLE (8075 1375);
FORCEPROP 2 LAST PATH I182
J 0
(8025 1525);
DISPLAY 1.021277 (8025 1525);
PAINT ORANGE (8025 1525);
DISPLAY INVISIBLE (8025 1525);
FORCEADD OFFPAGE..6
(7975 1400);
FORCEPROP 2 LAST $XR0 21 
J 0
(7726 1400);
DISPLAY 0.638298 (7726 1400);
PAINT MONO (7726 1400);
FORCEPROP 2 LAST $XR1 112 
J 0
(7606 1400);
DISPLAY 0.638298 (7606 1400);
PAINT MONO (7606 1400);
FORCEPROP 2 LAST CDS_LIB mstr_standard
J 0
(7975 1400);
PAINT ORANGE (7975 1400);
DISPLAY INVISIBLE (7975 1400);
FORCEPROP 1 LAST OFFPAGE TRUE
J 0
(8300 1275);
DISPLAY 1.170213 (8300 1275);
PAINT GREEN (8300 1275);
DISPLAY INVISIBLE (8300 1275);
FORCEPROP 1 LAST COMMENT_BODY TRUE
J 0
(8075 1325);
DISPLAY 1.170213 (8075 1325);
PAINT GREEN (8075 1325);
DISPLAY INVISIBLE (8075 1325);
FORCEPROP 2 LAST PATH I183
J 0
(8025 1475);
DISPLAY 1.021277 (8025 1475);
PAINT ORANGE (8025 1475);
DISPLAY INVISIBLE (8025 1475);
FORCEADD OFFPAGE..4
(12550 1050);
FORCEPROP 2 LAST $XR0 112 
J 0
(12736 1050);
DISPLAY 0.638298 (12736 1050);
PAINT MONO (12736 1050);
FORCEPROP 2 LAST $XR1 21 
J 0
(12856 1050);
DISPLAY 0.638298 (12856 1050);
PAINT MONO (12856 1050);
FORCEPROP 2 LAST CDS_LIB mstr_standard
J 0
(12550 1050);
PAINT ORANGE (12550 1050);
DISPLAY INVISIBLE (12550 1050);
FORCEPROP 1 LAST OFFPAGE TRUE
J 0
(12875 925);
DISPLAY 1.170213 (12875 925);
PAINT GREEN (12875 925);
DISPLAY INVISIBLE (12875 925);
FORCEPROP 1 LAST COMMENT_BODY TRUE
J 0
(12525 950);
DISPLAY 1.170213 (12525 950);
PAINT GREEN (12525 950);
DISPLAY INVISIBLE (12525 950);
FORCEPROP 2 LAST PATH I184
J 0
(12725 1125);
DISPLAY 1.021277 (12725 1125);
PAINT ORANGE (12725 1125);
DISPLAY INVISIBLE (12725 1125);
FORCEADD OFFPAGE..2
(12550 1000);
FORCEPROP 2 LAST $XR0 21 
J 0
(12739 1000);
DISPLAY 0.638298 (12739 1000);
PAINT MONO (12739 1000);
FORCEPROP 2 LAST $XR1 112 
J 0
(12829 1000);
DISPLAY 0.638298 (12829 1000);
PAINT MONO (12829 1000);
FORCEPROP 2 LAST CDS_LIB mstr_standard
J 0
(12550 1000);
PAINT ORANGE (12550 1000);
DISPLAY INVISIBLE (12550 1000);
FORCEPROP 1 LAST OFFPAGE TRUE
J 0
(12875 875);
DISPLAY 1.170213 (12875 875);
PAINT GREEN (12875 875);
DISPLAY INVISIBLE (12875 875);
FORCEPROP 1 LAST COMMENT_BODY TRUE
J 0
(12505 905);
DISPLAY 1.170213 (12505 905);
PAINT GREEN (12505 905);
DISPLAY INVISIBLE (12505 905);
FORCEPROP 2 LAST PATH I185
J 0
(12725 1075);
DISPLAY 1.021277 (12725 1075);
PAINT ORANGE (12725 1075);
DISPLAY INVISIBLE (12725 1075);
FORCEADD OFFPAGE..1
(8000 2150);
FORCEPROP 2 LAST $XR0 156 
J 0
(7748 2150);
DISPLAY 0.638298 (7748 2150);
PAINT MONO (7748 2150);
FORCEPROP 2 LAST CDS_LIB mstr_standard
J 0
(8000 2150);
PAINT ORANGE (8000 2150);
DISPLAY INVISIBLE (8000 2150);
FORCEPROP 1 LAST OFFPAGE TRUE
J 0
(8325 2025);
DISPLAY 0.872340 (8325 2025);
PAINT GREEN (8325 2025);
DISPLAY INVISIBLE (8325 2025);
FORCEPROP 1 LAST COMMENT_BODY TRUE
J 0
(8125 2050);
DISPLAY 0.872340 (8125 2050);
PAINT GREEN (8125 2050);
DISPLAY INVISIBLE (8125 2050);
FORCEPROP 2 LAST PATH I186
J 0
(8050 2225);
DISPLAY 1.021277 (8050 2225);
PAINT ORANGE (8050 2225);
DISPLAY INVISIBLE (8050 2225);
FORCEADD OFFPAGE..6
(8000 2100);
FORCEPROP 2 LAST $XR0 156 
J 0
(7546 2100);
DISPLAY 0.638298 (7546 2100);
PAINT MONO (7546 2100);
DISPLAY INVISIBLE (7546 2100);
FORCEPROP 2 LAST CDS_LIB mstr_standard
J 0
(8000 2100);
PAINT ORANGE (8000 2100);
DISPLAY INVISIBLE (8000 2100);
FORCEPROP 1 LAST OFFPAGE TRUE
J 0
(8325 1975);
DISPLAY 0.872340 (8325 1975);
PAINT GREEN (8325 1975);
DISPLAY INVISIBLE (8325 1975);
FORCEPROP 1 LAST COMMENT_BODY TRUE
J 0
(8100 2025);
DISPLAY 0.872340 (8100 2025);
PAINT GREEN (8100 2025);
DISPLAY INVISIBLE (8100 2025);
FORCEPROP 2 LAST PATH I187
J 0
(8050 2175);
DISPLAY 1.021277 (8050 2175);
PAINT ORANGE (8050 2175);
DISPLAY INVISIBLE (8050 2175);
FORCEADD OFFPAGE..4
(12525 1700);
FORCEPROP 2 LAST $XR0 156 
J 0
(12711 1700);
DISPLAY 0.638298 (12711 1700);
PAINT MONO (12711 1700);
FORCEPROP 2 LAST CDS_LIB mstr_standard
J 0
(12525 1700);
PAINT ORANGE (12525 1700);
DISPLAY INVISIBLE (12525 1700);
FORCEPROP 1 LAST OFFPAGE TRUE
J 0
(12850 1575);
DISPLAY 0.872340 (12850 1575);
PAINT GREEN (12850 1575);
DISPLAY INVISIBLE (12850 1575);
FORCEPROP 1 LAST COMMENT_BODY TRUE
J 0
(12500 1600);
DISPLAY 0.872340 (12500 1600);
PAINT GREEN (12500 1600);
DISPLAY INVISIBLE (12500 1600);
FORCEPROP 2 LAST PATH I188
J 0
(12575 1775);
DISPLAY 1.021277 (12575 1775);
PAINT ORANGE (12575 1775);
DISPLAY INVISIBLE (12575 1775);
FORCEADD OFFPAGE..4
(12525 1450);
FORCEPROP 2 LAST $XR0 156 
J 0
(12711 1450);
DISPLAY 0.638298 (12711 1450);
PAINT MONO (12711 1450);
FORCEPROP 2 LAST CDS_LIB mstr_standard
J 0
(12525 1450);
PAINT ORANGE (12525 1450);
DISPLAY INVISIBLE (12525 1450);
FORCEPROP 1 LAST OFFPAGE TRUE
J 0
(12850 1325);
DISPLAY 0.872340 (12850 1325);
PAINT GREEN (12850 1325);
DISPLAY INVISIBLE (12850 1325);
FORCEPROP 1 LAST COMMENT_BODY TRUE
J 0
(12500 1350);
DISPLAY 0.872340 (12500 1350);
PAINT GREEN (12500 1350);
DISPLAY INVISIBLE (12500 1350);
FORCEPROP 2 LAST PATH I189
J 0
(12700 1525);
DISPLAY 1.021277 (12700 1525);
PAINT ORANGE (12700 1525);
DISPLAY INVISIBLE (12700 1525);
FORCEADD RES..2
(13500 3225);
FORCEPROP 1 LAST LOCATION R3B2
J 0
(13545 3350);
DISPLAY 0.617021 (13545 3350);
PAINT AQUA (13545 3350);
FORCEPROP 1 LAST PART_NUMBER G21796-047
R 1
J 0
(13565 3025);
DISPLAY 0.617021 (13565 3025);
PAINT BLUE (13565 3025);
FORCEPROP 1 LAST VALUE 49.9
R 1
J 0
(13620 3200);
DISPLAY 0.617021 (13620 3200);
PAINT SKYBLUE (13620 3200);
FORCEPROP 1 LAST MATERIAL CHIP
R 1
J 0
(13615 3025);
DISPLAY 0.617021 (13615 3025);
PAINT SKYBLUE (13615 3025);
FORCEPROP 1 LASTPIN (13500 3125) $PN 2
J 0
(13505 3135);
DISPLAY 0.617021 (13505 3135);
PAINT GREEN (13505 3135);
FORCEPROP 1 LASTPIN (13500 3325) $PN 1
J 0
(13505 3287);
DISPLAY 0.617021 (13505 3287);
PAINT GREEN (13505 3287);
FORCEPROP 1 LAST TOLERANCE 1%
J 0
(13545 3250);
DISPLAY 0.978723 (13545 3250);
PAINT SKYBLUE (13545 3250);
DISPLAY INVISIBLE (13545 3250);
FORCEPROP 1 LAST PACK_TYPE 0402
J 0
(13540 3050);
DISPLAY 0.978723 (13540 3050);
PAINT SKYBLUE (13540 3050);
DISPLAY INVISIBLE (13540 3050);
FORCEPROP 1 LAST WATTAGE 1/16W
J 0
(13540 3200);
DISPLAY 0.978723 (13540 3200);
PAINT SKYBLUE (13540 3200);
DISPLAY INVISIBLE (13540 3200);
FORCEPROP 2 LAST CDS_LIB mstr_discrete
J 0
(13500 3225);
PAINT ORANGE (13500 3225);
DISPLAY INVISIBLE (13500 3225);
FORCEPROP 2 LAST SEC_TYPE 0402
J 0
(13550 3450);
DISPLAY 1.021277 (13550 3450);
PAINT ORANGE (13550 3450);
DISPLAY INVISIBLE (13550 3450);
FORCEPROP 2 LAST BOM_COST PROC_SOCKET
J 0
(13550 3450);
PAINT MONO (13550 3450);
DISPLAY INVISIBLE (13550 3450);
FORCEPROP 2 LAST SEC 1
J 0
(13550 3450);
DISPLAY 0.680851 (13550 3450);
PAINT MONO (13550 3450);
DISPLAY INVISIBLE (13550 3450);
FORCEPROP 2 LAST CDS_LOCATION R3B2
J 0
(13545 3350);
DISPLAY 0.617021 (13545 3350);
PAINT AQUA (13545 3350);
DISPLAY INVISIBLE (13545 3350);
FORCEPROP 1 LAST PATH I19
J 0
(13550 3400);
DISPLAY 0.978723 (13550 3400);
PAINT WHITE (13550 3400);
DISPLAY INVISIBLE (13550 3400);
FORCEPROP 2 LAST ROOM CPU1
J 0
(13550 3400);
PAINT MONO (13550 3400);
DISPLAY INVISIBLE (13550 3400);
FORCEADD OFFPAGE..4
(12525 1400);
FORCEPROP 2 LAST $XR0 156 
J 0
(12711 1400);
DISPLAY 0.638298 (12711 1400);
PAINT MONO (12711 1400);
FORCEPROP 2 LAST CDS_LIB mstr_standard
J 0
(12525 1400);
PAINT ORANGE (12525 1400);
DISPLAY INVISIBLE (12525 1400);
FORCEPROP 1 LAST OFFPAGE TRUE
J 0
(12850 1275);
DISPLAY 0.872340 (12850 1275);
PAINT GREEN (12850 1275);
DISPLAY INVISIBLE (12850 1275);
FORCEPROP 1 LAST COMMENT_BODY TRUE
J 0
(12500 1300);
DISPLAY 0.872340 (12500 1300);
PAINT GREEN (12500 1300);
DISPLAY INVISIBLE (12500 1300);
FORCEPROP 2 LAST PATH I190
J 0
(12700 1475);
DISPLAY 1.021277 (12700 1475);
PAINT ORANGE (12700 1475);
DISPLAY INVISIBLE (12700 1475);
FORCEADD OFFPAGE..4
(12525 1350);
FORCEPROP 2 LAST $XR0 156 
J 0
(12711 1350);
DISPLAY 0.638298 (12711 1350);
PAINT MONO (12711 1350);
FORCEPROP 2 LAST CDS_LIB mstr_standard
J 0
(12525 1350);
PAINT ORANGE (12525 1350);
DISPLAY INVISIBLE (12525 1350);
FORCEPROP 1 LAST OFFPAGE TRUE
J 0
(12850 1225);
DISPLAY 0.872340 (12850 1225);
PAINT GREEN (12850 1225);
DISPLAY INVISIBLE (12850 1225);
FORCEPROP 1 LAST COMMENT_BODY TRUE
J 0
(12500 1250);
DISPLAY 0.872340 (12500 1250);
PAINT GREEN (12500 1250);
DISPLAY INVISIBLE (12500 1250);
FORCEPROP 2 LAST PATH I191
J 0
(12700 1425);
DISPLAY 1.021277 (12700 1425);
PAINT ORANGE (12700 1425);
DISPLAY INVISIBLE (12700 1425);
FORCEADD OFFPAGE..6
(7975 1150);
FORCEPROP 2 LAST $XR0 21 
J 0
(7726 1150);
DISPLAY 0.638298 (7726 1150);
PAINT MONO (7726 1150);
FORCEPROP 2 LAST $XR1 112 
J 0
(7606 1150);
DISPLAY 0.638298 (7606 1150);
PAINT MONO (7606 1150);
FORCEPROP 2 LAST CDS_LIB mstr_standard
J 0
(7975 1150);
PAINT MONO (7975 1150);
DISPLAY INVISIBLE (7975 1150);
FORCEPROP 1 LAST OFFPAGE TRUE
J 0
(8300 1025);
DISPLAY 1.170213 (8300 1025);
PAINT GREEN (8300 1025);
DISPLAY INVISIBLE (8300 1025);
FORCEPROP 1 LAST COMMENT_BODY TRUE
J 0
(8075 1075);
DISPLAY 1.170213 (8075 1075);
PAINT GREEN (8075 1075);
DISPLAY INVISIBLE (8075 1075);
FORCEPROP 2 LAST PATH I2
J 0
(8025 1225);
DISPLAY 1.021277 (8025 1225);
PAINT ORANGE (8025 1225);
DISPLAY INVISIBLE (8025 1225);
FORCEADD RES..2
(13300 3225);
FORCEPROP 1 LAST LOCATION R3B4
J 0
(13345 3350);
DISPLAY 0.617021 (13345 3350);
PAINT AQUA (13345 3350);
FORCEPROP 1 LAST PART_NUMBER G21796-017
R 1
J 0
(13365 3025);
DISPLAY 0.617021 (13365 3025);
PAINT BLUE (13365 3025);
FORCEPROP 1 LAST VALUE 100.0
R 1
J 0
(13420 3200);
DISPLAY 0.617021 (13420 3200);
PAINT SKYBLUE (13420 3200);
FORCEPROP 1 LAST MATERIAL CHIP
R 1
J 0
(13415 3025);
DISPLAY 0.617021 (13415 3025);
PAINT SKYBLUE (13415 3025);
FORCEPROP 1 LASTPIN (13300 3125) $PN 2
J 0
(13305 3135);
DISPLAY 0.617021 (13305 3135);
PAINT GREEN (13305 3135);
FORCEPROP 1 LASTPIN (13300 3325) $PN 1
J 0
(13305 3287);
DISPLAY 0.617021 (13305 3287);
PAINT GREEN (13305 3287);
FORCEPROP 1 LAST TOLERANCE 1%
J 0
(13345 3250);
DISPLAY 0.978723 (13345 3250);
PAINT SKYBLUE (13345 3250);
DISPLAY INVISIBLE (13345 3250);
FORCEPROP 1 LAST PACK_TYPE 0402
J 0
(13340 3050);
DISPLAY 0.978723 (13340 3050);
PAINT SKYBLUE (13340 3050);
DISPLAY INVISIBLE (13340 3050);
FORCEPROP 1 LAST WATTAGE 1/16W
J 0
(13340 3200);
DISPLAY 0.978723 (13340 3200);
PAINT SKYBLUE (13340 3200);
DISPLAY INVISIBLE (13340 3200);
FORCEPROP 2 LAST CDS_LIB mstr_discrete
J 0
(13300 3225);
PAINT ORANGE (13300 3225);
DISPLAY INVISIBLE (13300 3225);
FORCEPROP 2 LAST SEC_TYPE 0402
J 0
(13350 3450);
DISPLAY 1.021277 (13350 3450);
PAINT ORANGE (13350 3450);
DISPLAY INVISIBLE (13350 3450);
FORCEPROP 2 LAST BOM_COST PROC_SOCKET
J 0
(13350 3450);
PAINT MONO (13350 3450);
DISPLAY INVISIBLE (13350 3450);
FORCEPROP 2 LAST SEC 1
J 0
(13350 3450);
DISPLAY 0.680851 (13350 3450);
PAINT MONO (13350 3450);
DISPLAY INVISIBLE (13350 3450);
FORCEPROP 2 LAST CDS_LOCATION R3B4
J 0
(13345 3350);
DISPLAY 0.617021 (13345 3350);
PAINT AQUA (13345 3350);
DISPLAY INVISIBLE (13345 3350);
FORCEPROP 1 LAST PATH I21
J 0
(13350 3400);
DISPLAY 0.978723 (13350 3400);
PAINT WHITE (13350 3400);
DISPLAY INVISIBLE (13350 3400);
FORCEPROP 2 LAST ROOM CPU1
J 0
(13350 3400);
PAINT MONO (13350 3400);
DISPLAY INVISIBLE (13350 3400);
FORCEADD PVCCIO_CPU1..1
(13850 3025);
FORCEPROP 3 LASTPIN (13850 2975) SIG_NAME PVCCIO_CPU1\g
J 0
(13860 2985);
DISPLAY 0.659574 (13860 2985);
PAINT MONO (13860 2985);
DISPLAY INVISIBLE (13860 2985);
FORCEPROP 1 LAST VOLTAGE 1.1V
J 0
(13805 2982);
DISPLAY 0.340426 (13805 2982);
PAINT SKYBLUE (13805 2982);
DISPLAY INVISIBLE (13805 2982);
FORCEPROP 2 LAST CDS_LIB mstr_symbols
J 0
(13850 3025);
PAINT ORANGE (13850 3025);
DISPLAY INVISIBLE (13850 3025);
FORCEPROP 1 LAST BODY_TYPE PLUMBING
J 0
(13805 2982);
DISPLAY 0.340426 (13805 2982);
PAINT GREEN (13805 2982);
DISPLAY INVISIBLE (13805 2982);
FORCEPROP 1 LAST PATH I22
J 0
(13900 3050);
DISPLAY 0.872340 (13900 3050);
PAINT AQUA (13900 3050);
DISPLAY INVISIBLE (13900 3050);
FORCEPROP 1 LAST HDL_POWER PVCCIO_CPU1
J 1
(13850 3075);
DISPLAY 0.872340 (13850 3075);
PAINT GREEN (13850 3075);
DISPLAY INVISIBLE (13850 3075);
FORCEADD OFFPAGE..3
(12525 3750);
FORCEPROP 2 LAST $XR0 21 
J 0
(12739 3750);
DISPLAY 0.638298 (12739 3750);
PAINT MONO (12739 3750);
FORCEPROP 2 LAST $XR1 166 
J 0
(12829 3750);
DISPLAY 0.638298 (12829 3750);
PAINT MONO (12829 3750);
FORCEPROP 2 LAST CDS_LIB mstr_standard
J 0
(12525 3750);
PAINT MONO (12525 3750);
DISPLAY INVISIBLE (12525 3750);
FORCEPROP 1 LAST OFFPAGE TRUE
J 0
(12850 3625);
DISPLAY 1.170213 (12850 3625);
PAINT GREEN (12850 3625);
DISPLAY INVISIBLE (12850 3625);
FORCEPROP 1 LAST COMMENT_BODY TRUE
J 0
(12475 3650);
DISPLAY 1.170213 (12475 3650);
PAINT GREEN (12475 3650);
DISPLAY INVISIBLE (12475 3650);
FORCEPROP 2 LAST PATH I23
J 0
(13075 3800);
DISPLAY 1.021277 (13075 3800);
PAINT ORANGE (13075 3800);
DISPLAY INVISIBLE (13075 3800);
FORCEADD RES..1
(12300 3650);
FORCEPROP 1 LAST LOCATION R1C2
J 0
(11825 3625);
DISPLAY 0.617021 (11825 3625);
PAINT AQUA (11825 3625);
FORCEPROP 1 LAST PART_NUMBER G21497-005
J 0
(12000 3625);
DISPLAY 0.617021 (12000 3625);
PAINT BLUE (12000 3625);
FORCEPROP 1 LAST VALUE 0.0
J 2
(12500 3625);
DISPLAY 0.617021 (12500 3625);
PAINT SKYBLUE (12500 3625);
FORCEPROP 1 LAST TOLERANCE 5%
J 0
(12525 3625);
DISPLAY 0.617021 (12525 3625);
PAINT SKYBLUE (12525 3625);
FORCEPROP 1 LAST PACK_TYPE 0402
J 0
(12600 3625);
DISPLAY 0.617021 (12600 3625);
PAINT SKYBLUE (12600 3625);
FORCEPROP 1 LASTPIN (12400 3650) $PN 2
J 0
(12362 3662);
DISPLAY 0.617021 (12362 3662);
PAINT GREEN (12362 3662);
FORCEPROP 1 LASTPIN (12200 3650) $PN 1
J 0
(12212 3662);
DISPLAY 0.617021 (12212 3662);
PAINT GREEN (12212 3662);
FORCEPROP 1 LAST MATERIAL CHIP
J 0
(12450 3550);
PAINT SKYBLUE (12450 3550);
DISPLAY INVISIBLE (12450 3550);
FORCEPROP 1 LAST WATTAGE 1/16W
J 2
(12825 3625);
DISPLAY 0.553191 (12825 3625);
PAINT SKYBLUE (12825 3625);
DISPLAY INVISIBLE (12825 3625);
FORCEPROP 2 LAST CDS_LIB mstr_discrete
J 0
(12300 3650);
DISPLAY 1.340426 (12300 3650);
PAINT ORANGE (12300 3650);
DISPLAY INVISIBLE (12300 3650);
FORCEPROP 2 LAST BOM_COST PROC_SOCKET
J 0
(12600 3725);
PAINT MONO (12600 3725);
DISPLAY INVISIBLE (12600 3725);
FORCEPROP 2 LAST CDS_SEC 1
J 0
(12250 3850);
DISPLAY 1.340426 (12250 3850);
PAINT MONO (12250 3850);
DISPLAY INVISIBLE (12250 3850);
FORCEPROP 2 LAST $SEC 1
J 0
(12250 3850);
DISPLAY 1.340426 (12250 3850);
PAINT MONO (12250 3850);
DISPLAY INVISIBLE (12250 3850);
FORCEPROP 2 LAST CDS_LOCATION R1C2
J 0
(11825 3625);
DISPLAY 0.617021 (11825 3625);
PAINT AQUA (11825 3625);
DISPLAY INVISIBLE (11825 3625);
FORCEPROP 1 LAST PATH I24
J 0
(12250 3800);
DISPLAY 0.978723 (12250 3800);
PAINT WHITE (12250 3800);
DISPLAY INVISIBLE (12250 3800);
FORCEPROP 2 LAST ROOM CPU1
J 0
(12600 3675);
PAINT MONO (12600 3675);
DISPLAY INVISIBLE (12600 3675);
FORCEADD RES..1
(12300 3600);
FORCEPROP 1 LAST LOCATION R1C3
J 0
(11825 3575);
DISPLAY 0.617021 (11825 3575);
PAINT AQUA (11825 3575);
FORCEPROP 1 LAST PART_NUMBER G21497-005
J 0
(12000 3575);
DISPLAY 0.617021 (12000 3575);
PAINT BLUE (12000 3575);
FORCEPROP 1 LAST VALUE 0.0
J 2
(12500 3575);
DISPLAY 0.617021 (12500 3575);
PAINT SKYBLUE (12500 3575);
FORCEPROP 1 LAST TOLERANCE 5%
J 0
(12525 3575);
DISPLAY 0.617021 (12525 3575);
PAINT SKYBLUE (12525 3575);
FORCEPROP 1 LAST PACK_TYPE 0402
J 0
(12600 3575);
DISPLAY 0.617021 (12600 3575);
PAINT SKYBLUE (12600 3575);
FORCEPROP 1 LASTPIN (12400 3600) $PN 2
J 0
(12362 3612);
DISPLAY 0.617021 (12362 3612);
PAINT GREEN (12362 3612);
FORCEPROP 1 LASTPIN (12200 3600) $PN 1
J 0
(12212 3612);
DISPLAY 0.617021 (12212 3612);
PAINT GREEN (12212 3612);
FORCEPROP 1 LAST MATERIAL CHIP
J 0
(12450 3500);
PAINT SKYBLUE (12450 3500);
DISPLAY INVISIBLE (12450 3500);
FORCEPROP 1 LAST WATTAGE 1/16W
J 2
(12825 3575);
DISPLAY 0.553191 (12825 3575);
PAINT SKYBLUE (12825 3575);
DISPLAY INVISIBLE (12825 3575);
FORCEPROP 2 LAST CDS_LIB mstr_discrete
J 0
(12300 3600);
DISPLAY 1.340426 (12300 3600);
PAINT ORANGE (12300 3600);
DISPLAY INVISIBLE (12300 3600);
FORCEPROP 2 LAST BOM_COST PROC_SOCKET
J 0
(12600 3675);
PAINT MONO (12600 3675);
DISPLAY INVISIBLE (12600 3675);
FORCEPROP 2 LAST CDS_SEC 1
J 0
(12250 3800);
DISPLAY 1.340426 (12250 3800);
PAINT MONO (12250 3800);
DISPLAY INVISIBLE (12250 3800);
FORCEPROP 2 LAST $SEC 1
J 0
(12250 3800);
DISPLAY 1.340426 (12250 3800);
PAINT MONO (12250 3800);
DISPLAY INVISIBLE (12250 3800);
FORCEPROP 2 LAST CDS_LOCATION R1C3
J 0
(11825 3575);
DISPLAY 0.617021 (11825 3575);
PAINT AQUA (11825 3575);
DISPLAY INVISIBLE (11825 3575);
FORCEPROP 1 LAST PATH I25
J 0
(12250 3750);
DISPLAY 0.978723 (12250 3750);
PAINT WHITE (12250 3750);
DISPLAY INVISIBLE (12250 3750);
FORCEPROP 2 LAST ROOM CPU1
J 0
(12600 3625);
PAINT MONO (12600 3625);
DISPLAY INVISIBLE (12600 3625);
FORCEADD RES..1
(12300 3550);
FORCEPROP 1 LAST LOCATION R1C1
J 0
(11825 3525);
DISPLAY 0.617021 (11825 3525);
PAINT AQUA (11825 3525);
FORCEPROP 1 LAST PART_NUMBER G21796-271
J 0
(12000 3525);
DISPLAY 0.617021 (12000 3525);
PAINT BLUE (12000 3525);
FORCEPROP 1 LAST VALUE 221
J 2
(12500 3525);
DISPLAY 0.617021 (12500 3525);
PAINT SKYBLUE (12500 3525);
FORCEPROP 1 LAST TOLERANCE 1.0%
J 0
(12500 3525);
DISPLAY 0.617021 (12500 3525);
PAINT SKYBLUE (12500 3525);
FORCEPROP 1 LAST PACK_TYPE 0402
J 0
(12625 3525);
DISPLAY 0.617021 (12625 3525);
PAINT SKYBLUE (12625 3525);
FORCEPROP 1 LASTPIN (12400 3550) $PN 2
J 0
(12362 3562);
DISPLAY 0.617021 (12362 3562);
PAINT GREEN (12362 3562);
FORCEPROP 1 LASTPIN (12200 3550) $PN 1
J 0
(12212 3562);
DISPLAY 0.617021 (12212 3562);
PAINT GREEN (12212 3562);
FORCEPROP 1 LAST MATERIAL CHIP
J 0
(12450 3450);
PAINT SKYBLUE (12450 3450);
DISPLAY INVISIBLE (12450 3450);
FORCEPROP 1 LAST WATTAGE 1/16W
J 2
(12825 3525);
DISPLAY 0.553191 (12825 3525);
PAINT SKYBLUE (12825 3525);
DISPLAY INVISIBLE (12825 3525);
FORCEPROP 2 LAST CDS_LIB mstr_discrete
J 0
(12300 3550);
DISPLAY 1.340426 (12300 3550);
PAINT ORANGE (12300 3550);
DISPLAY INVISIBLE (12300 3550);
FORCEPROP 2 LAST BOM_COST PROC_SOCKET
J 0
(12600 3625);
PAINT MONO (12600 3625);
DISPLAY INVISIBLE (12600 3625);
FORCEPROP 2 LAST CDS_SEC 1
J 0
(12250 3750);
DISPLAY 1.340426 (12250 3750);
PAINT MONO (12250 3750);
DISPLAY INVISIBLE (12250 3750);
FORCEPROP 2 LAST $SEC 1
J 0
(12250 3750);
DISPLAY 1.340426 (12250 3750);
PAINT MONO (12250 3750);
DISPLAY INVISIBLE (12250 3750);
FORCEPROP 2 LAST CDS_LOCATION R1C1
J 0
(11825 3525);
DISPLAY 0.617021 (11825 3525);
PAINT AQUA (11825 3525);
DISPLAY INVISIBLE (11825 3525);
FORCEPROP 1 LAST PATH I26
J 0
(12250 3700);
DISPLAY 0.978723 (12250 3700);
PAINT WHITE (12250 3700);
DISPLAY INVISIBLE (12250 3700);
FORCEPROP 2 LAST ROOM CPU1
J 0
(12600 3575);
PAINT MONO (12600 3575);
DISPLAY INVISIBLE (12600 3575);
FORCEADD RES..1
(12300 3400);
FORCEPROP 1 LAST LOCATION R3B1
J 0
(11825 3375);
DISPLAY 0.617021 (11825 3375);
PAINT AQUA (11825 3375);
FORCEPROP 1 LAST PART_NUMBER G21796-271
J 0
(12000 3375);
DISPLAY 0.617021 (12000 3375);
PAINT BLUE (12000 3375);
FORCEPROP 1 LAST VALUE 221
J 2
(12500 3375);
DISPLAY 0.617021 (12500 3375);
PAINT SKYBLUE (12500 3375);
FORCEPROP 1 LAST TOLERANCE 1.0%
J 0
(12525 3375);
DISPLAY 0.617021 (12525 3375);
PAINT SKYBLUE (12525 3375);
FORCEPROP 1 LAST PACK_TYPE 0402
J 0
(12650 3375);
DISPLAY 0.617021 (12650 3375);
PAINT SKYBLUE (12650 3375);
FORCEPROP 1 LASTPIN (12400 3400) $PN 2
J 0
(12362 3412);
DISPLAY 0.617021 (12362 3412);
PAINT GREEN (12362 3412);
FORCEPROP 1 LASTPIN (12200 3400) $PN 1
J 0
(12212 3412);
DISPLAY 0.617021 (12212 3412);
PAINT GREEN (12212 3412);
FORCEPROP 1 LAST MATERIAL CHIP
J 0
(12450 3300);
PAINT SKYBLUE (12450 3300);
DISPLAY INVISIBLE (12450 3300);
FORCEPROP 1 LAST WATTAGE 1/16W
J 2
(12825 3375);
DISPLAY 0.553191 (12825 3375);
PAINT SKYBLUE (12825 3375);
DISPLAY INVISIBLE (12825 3375);
FORCEPROP 2 LAST CDS_LIB mstr_discrete
J 0
(12300 3400);
DISPLAY 1.340426 (12300 3400);
PAINT ORANGE (12300 3400);
DISPLAY INVISIBLE (12300 3400);
FORCEPROP 2 LAST BOM_COST PROC_SOCKET
J 0
(12600 3475);
PAINT MONO (12600 3475);
DISPLAY INVISIBLE (12600 3475);
FORCEPROP 2 LAST CDS_SEC 1
J 0
(12250 3600);
DISPLAY 1.340426 (12250 3600);
PAINT MONO (12250 3600);
DISPLAY INVISIBLE (12250 3600);
FORCEPROP 2 LAST $SEC 1
J 0
(12250 3600);
DISPLAY 1.340426 (12250 3600);
PAINT MONO (12250 3600);
DISPLAY INVISIBLE (12250 3600);
FORCEPROP 2 LAST CDS_LOCATION R3B1
J 0
(11825 3375);
DISPLAY 0.617021 (11825 3375);
PAINT AQUA (11825 3375);
DISPLAY INVISIBLE (11825 3375);
FORCEPROP 1 LAST PATH I27
J 0
(12250 3550);
DISPLAY 0.978723 (12250 3550);
PAINT WHITE (12250 3550);
DISPLAY INVISIBLE (12250 3550);
FORCEPROP 2 LAST ROOM CPU1
J 0
(12600 3425);
PAINT MONO (12600 3425);
DISPLAY INVISIBLE (12600 3425);
FORCEADD RES..1
(12300 3450);
FORCEPROP 1 LAST LOCATION R3B5
J 0
(11825 3425);
DISPLAY 0.617021 (11825 3425);
PAINT AQUA (11825 3425);
FORCEPROP 1 LAST PART_NUMBER G21497-005
J 0
(12000 3425);
DISPLAY 0.617021 (12000 3425);
PAINT BLUE (12000 3425);
FORCEPROP 1 LAST VALUE 0.0
J 2
(12500 3425);
DISPLAY 0.617021 (12500 3425);
PAINT SKYBLUE (12500 3425);
FORCEPROP 1 LAST TOLERANCE 5%
J 0
(12550 3425);
DISPLAY 0.617021 (12550 3425);
PAINT SKYBLUE (12550 3425);
FORCEPROP 1 LAST PACK_TYPE 0402
J 0
(12650 3425);
DISPLAY 0.617021 (12650 3425);
PAINT SKYBLUE (12650 3425);
FORCEPROP 1 LASTPIN (12400 3450) $PN 2
J 0
(12362 3462);
DISPLAY 0.617021 (12362 3462);
PAINT GREEN (12362 3462);
FORCEPROP 1 LASTPIN (12200 3450) $PN 1
J 0
(12212 3462);
DISPLAY 0.617021 (12212 3462);
PAINT GREEN (12212 3462);
FORCEPROP 1 LAST MATERIAL CHIP
J 0
(12450 3350);
PAINT SKYBLUE (12450 3350);
DISPLAY INVISIBLE (12450 3350);
FORCEPROP 1 LAST WATTAGE 1/16W
J 2
(12825 3425);
DISPLAY 0.553191 (12825 3425);
PAINT SKYBLUE (12825 3425);
DISPLAY INVISIBLE (12825 3425);
FORCEPROP 2 LAST CDS_LIB mstr_discrete
J 0
(12300 3450);
DISPLAY 1.340426 (12300 3450);
PAINT ORANGE (12300 3450);
DISPLAY INVISIBLE (12300 3450);
FORCEPROP 2 LAST BOM_COST PROC_SOCKET
J 0
(12600 3525);
PAINT MONO (12600 3525);
DISPLAY INVISIBLE (12600 3525);
FORCEPROP 2 LAST CDS_SEC 1
J 0
(12250 3650);
DISPLAY 1.340426 (12250 3650);
PAINT MONO (12250 3650);
DISPLAY INVISIBLE (12250 3650);
FORCEPROP 2 LAST $SEC 1
J 0
(12250 3650);
DISPLAY 1.340426 (12250 3650);
PAINT MONO (12250 3650);
DISPLAY INVISIBLE (12250 3650);
FORCEPROP 2 LAST CDS_LOCATION R3B5
J 0
(11825 3425);
DISPLAY 0.617021 (11825 3425);
PAINT AQUA (11825 3425);
DISPLAY INVISIBLE (11825 3425);
FORCEPROP 1 LAST PATH I28
J 0
(12250 3600);
DISPLAY 0.978723 (12250 3600);
PAINT WHITE (12250 3600);
DISPLAY INVISIBLE (12250 3600);
FORCEPROP 2 LAST ROOM CPU1
J 0
(12600 3475);
PAINT MONO (12600 3475);
DISPLAY INVISIBLE (12600 3475);
FORCEADD RES..1
(12300 3500);
FORCEPROP 1 LAST LOCATION R3B3
J 0
(11825 3475);
DISPLAY 0.617021 (11825 3475);
PAINT AQUA (11825 3475);
FORCEPROP 1 LAST PART_NUMBER G21497-005
J 0
(12000 3475);
DISPLAY 0.617021 (12000 3475);
PAINT BLUE (12000 3475);
FORCEPROP 1 LAST VALUE 0.0
J 2
(12500 3475);
DISPLAY 0.617021 (12500 3475);
PAINT SKYBLUE (12500 3475);
FORCEPROP 1 LAST TOLERANCE 5%
J 0
(12550 3475);
DISPLAY 0.617021 (12550 3475);
PAINT SKYBLUE (12550 3475);
FORCEPROP 1 LAST PACK_TYPE 0402
J 0
(12625 3475);
DISPLAY 0.617021 (12625 3475);
PAINT SKYBLUE (12625 3475);
FORCEPROP 1 LASTPIN (12400 3500) $PN 2
J 0
(12362 3512);
DISPLAY 0.617021 (12362 3512);
PAINT GREEN (12362 3512);
FORCEPROP 1 LASTPIN (12200 3500) $PN 1
J 0
(12212 3512);
DISPLAY 0.617021 (12212 3512);
PAINT GREEN (12212 3512);
FORCEPROP 1 LAST MATERIAL CHIP
J 0
(12450 3400);
PAINT SKYBLUE (12450 3400);
DISPLAY INVISIBLE (12450 3400);
FORCEPROP 1 LAST WATTAGE 1/16W
J 2
(12825 3475);
DISPLAY 0.553191 (12825 3475);
PAINT SKYBLUE (12825 3475);
DISPLAY INVISIBLE (12825 3475);
FORCEPROP 2 LAST CDS_LIB mstr_discrete
J 0
(12300 3500);
DISPLAY 1.340426 (12300 3500);
PAINT ORANGE (12300 3500);
DISPLAY INVISIBLE (12300 3500);
FORCEPROP 2 LAST BOM_COST PROC_SOCKET
J 0
(12600 3575);
PAINT MONO (12600 3575);
DISPLAY INVISIBLE (12600 3575);
FORCEPROP 2 LAST CDS_SEC 1
J 0
(12250 3700);
DISPLAY 1.340426 (12250 3700);
PAINT MONO (12250 3700);
DISPLAY INVISIBLE (12250 3700);
FORCEPROP 2 LAST $SEC 1
J 0
(12250 3700);
DISPLAY 1.340426 (12250 3700);
PAINT MONO (12250 3700);
DISPLAY INVISIBLE (12250 3700);
FORCEPROP 2 LAST CDS_LOCATION R3B3
J 0
(11825 3475);
DISPLAY 0.617021 (11825 3475);
PAINT AQUA (11825 3475);
DISPLAY INVISIBLE (11825 3475);
FORCEPROP 1 LAST PATH I29
J 0
(12250 3650);
DISPLAY 0.978723 (12250 3650);
PAINT WHITE (12250 3650);
DISPLAY INVISIBLE (12250 3650);
FORCEPROP 2 LAST ROOM CPU1
J 0
(12600 3525);
PAINT MONO (12600 3525);
DISPLAY INVISIBLE (12600 3525);
FORCEADD OFFPAGE..6
(7975 1100);
FORCEPROP 2 LAST $XR0 21 
J 0
(7726 1100);
DISPLAY 0.638298 (7726 1100);
PAINT MONO (7726 1100);
FORCEPROP 2 LAST $XR1 112 
J 0
(7606 1100);
DISPLAY 0.638298 (7606 1100);
PAINT MONO (7606 1100);
FORCEPROP 2 LAST CDS_LIB mstr_standard
J 0
(7975 1100);
PAINT MONO (7975 1100);
DISPLAY INVISIBLE (7975 1100);
FORCEPROP 1 LAST OFFPAGE TRUE
J 0
(8300 975);
DISPLAY 1.170213 (8300 975);
PAINT GREEN (8300 975);
DISPLAY INVISIBLE (8300 975);
FORCEPROP 1 LAST COMMENT_BODY TRUE
J 0
(8075 1025);
DISPLAY 1.170213 (8075 1025);
PAINT GREEN (8075 1025);
DISPLAY INVISIBLE (8075 1025);
FORCEPROP 2 LAST PATH I3
J 0
(8025 1175);
DISPLAY 1.021277 (8025 1175);
PAINT ORANGE (8025 1175);
DISPLAY INVISIBLE (8025 1175);
FORCEADD OFFPAGE..3
(12500 3300);
FORCEPROP 2 LAST $XR0 92 
J 0
(12714 3300);
DISPLAY 0.638298 (12714 3300);
PAINT MONO (12714 3300);
FORCEPROP 2 LAST CDS_LIB mstr_standard
J 0
(12500 3300);
PAINT MONO (12500 3300);
DISPLAY INVISIBLE (12500 3300);
FORCEPROP 1 LAST OFFPAGE TRUE
J 0
(12825 3175);
DISPLAY 0.872340 (12825 3175);
PAINT GREEN (12825 3175);
DISPLAY INVISIBLE (12825 3175);
FORCEPROP 1 LAST COMMENT_BODY TRUE
J 0
(12450 3200);
DISPLAY 0.872340 (12450 3200);
PAINT GREEN (12450 3200);
DISPLAY INVISIBLE (12450 3200);
FORCEPROP 2 LAST PATH I30
J 0
(12700 3350);
DISPLAY 1.021277 (12700 3350);
PAINT ORANGE (12700 3350);
DISPLAY INVISIBLE (12700 3350);
FORCEADD OFFPAGE..2
(12525 3200);
FORCEPROP 2 LAST $XR0 92 
J 0
(12714 3200);
DISPLAY 0.638298 (12714 3200);
PAINT MONO (12714 3200);
FORCEPROP 2 LAST CDS_LIB mstr_standard
J 0
(12525 3200);
PAINT MONO (12525 3200);
DISPLAY INVISIBLE (12525 3200);
FORCEPROP 1 LAST OFFPAGE TRUE
J 0
(12850 3075);
DISPLAY 0.872340 (12850 3075);
PAINT GREEN (12850 3075);
DISPLAY INVISIBLE (12850 3075);
FORCEPROP 1 LAST COMMENT_BODY TRUE
J 0
(12480 3105);
DISPLAY 0.872340 (12480 3105);
PAINT GREEN (12480 3105);
DISPLAY INVISIBLE (12480 3105);
FORCEPROP 2 LAST PATH I31
J 0
(12725 3250);
DISPLAY 1.021277 (12725 3250);
PAINT ORANGE (12725 3250);
DISPLAY INVISIBLE (12725 3250);
FORCEADD OFFPAGE..3
(12500 3000);
FORCEPROP 2 LAST $XR0 92 
J 0
(12714 3000);
DISPLAY 0.638298 (12714 3000);
PAINT MONO (12714 3000);
FORCEPROP 2 LAST CDS_LIB mstr_standard
J 0
(12500 3000);
PAINT MONO (12500 3000);
DISPLAY INVISIBLE (12500 3000);
FORCEPROP 1 LAST OFFPAGE TRUE
J 0
(12825 2875);
DISPLAY 1.170213 (12825 2875);
PAINT GREEN (12825 2875);
DISPLAY INVISIBLE (12825 2875);
FORCEPROP 1 LAST COMMENT_BODY TRUE
J 0
(12450 2900);
DISPLAY 1.170213 (12450 2900);
PAINT GREEN (12450 2900);
DISPLAY INVISIBLE (12450 2900);
FORCEPROP 2 LAST PATH I32
J 0
(12700 3075);
DISPLAY 1.021277 (12700 3075);
PAINT ORANGE (12700 3075);
DISPLAY INVISIBLE (12700 3075);
FORCEADD OFFPAGE..2
(12525 3100);
FORCEPROP 2 LAST $XR0 93 
J 0
(12714 3100);
DISPLAY 0.638298 (12714 3100);
PAINT MONO (12714 3100);
FORCEPROP 2 LAST CDS_LIB mstr_standard
J 0
(12525 3100);
PAINT MONO (12525 3100);
DISPLAY INVISIBLE (12525 3100);
FORCEPROP 1 LAST OFFPAGE TRUE
J 0
(12850 2975);
DISPLAY 0.872340 (12850 2975);
PAINT GREEN (12850 2975);
DISPLAY INVISIBLE (12850 2975);
FORCEPROP 1 LAST COMMENT_BODY TRUE
J 0
(12480 3005);
DISPLAY 0.872340 (12480 3005);
PAINT GREEN (12480 3005);
DISPLAY INVISIBLE (12480 3005);
FORCEPROP 2 LAST PATH I33
J 0
(12700 3175);
DISPLAY 1.021277 (12700 3175);
PAINT ORANGE (12700 3175);
DISPLAY INVISIBLE (12700 3175);
FORCEADD OFFPAGE..2
(12525 3150);
FORCEPROP 2 LAST $XR0 93 
J 0
(12714 3150);
DISPLAY 0.638298 (12714 3150);
PAINT MONO (12714 3150);
FORCEPROP 2 LAST CDS_LIB mstr_standard
J 0
(12525 3150);
PAINT MONO (12525 3150);
DISPLAY INVISIBLE (12525 3150);
FORCEPROP 1 LAST OFFPAGE TRUE
J 0
(12850 3025);
DISPLAY 0.872340 (12850 3025);
PAINT GREEN (12850 3025);
DISPLAY INVISIBLE (12850 3025);
FORCEPROP 1 LAST COMMENT_BODY TRUE
J 0
(12480 3055);
DISPLAY 0.872340 (12480 3055);
PAINT GREEN (12480 3055);
DISPLAY INVISIBLE (12480 3055);
FORCEPROP 2 LAST PATH I34
J 0
(12700 3225);
DISPLAY 1.021277 (12700 3225);
PAINT ORANGE (12700 3225);
DISPLAY INVISIBLE (12700 3225);
FORCEADD OFFPAGE..3
(12500 2850);
FORCEPROP 2 LAST $XR0 95 
J 0
(12714 2850);
DISPLAY 0.638298 (12714 2850);
PAINT MONO (12714 2850);
FORCEPROP 2 LAST $XR1 93 
J 0
(12804 2850);
DISPLAY 0.638298 (12804 2850);
PAINT MONO (12804 2850);
FORCEPROP 2 LAST CDS_LIB mstr_standard
J 0
(12500 2850);
PAINT MONO (12500 2850);
DISPLAY INVISIBLE (12500 2850);
FORCEPROP 1 LAST OFFPAGE TRUE
J 0
(12825 2725);
DISPLAY 1.170213 (12825 2725);
PAINT GREEN (12825 2725);
DISPLAY INVISIBLE (12825 2725);
FORCEPROP 1 LAST COMMENT_BODY TRUE
J 0
(12450 2750);
DISPLAY 1.170213 (12450 2750);
PAINT GREEN (12450 2750);
DISPLAY INVISIBLE (12450 2750);
FORCEPROP 2 LAST PATH I36
J 0
(13050 2900);
DISPLAY 1.021277 (13050 2900);
PAINT ORANGE (13050 2900);
DISPLAY INVISIBLE (13050 2900);
FORCEADD OFFPAGE..2
(12525 2800);
FORCEPROP 2 LAST $XR0 92 
J 0
(12714 2800);
DISPLAY 0.638298 (12714 2800);
PAINT MONO (12714 2800);
FORCEPROP 2 LAST CDS_LIB mstr_standard
J 0
(12525 2800);
PAINT MONO (12525 2800);
DISPLAY INVISIBLE (12525 2800);
FORCEPROP 1 LAST OFFPAGE TRUE
J 0
(12850 2675);
DISPLAY 1.170213 (12850 2675);
PAINT GREEN (12850 2675);
DISPLAY INVISIBLE (12850 2675);
FORCEPROP 1 LAST COMMENT_BODY TRUE
J 0
(12480 2705);
DISPLAY 1.170213 (12480 2705);
PAINT GREEN (12480 2705);
DISPLAY INVISIBLE (12480 2705);
FORCEPROP 2 LAST PATH I37
J 0
(12825 2850);
DISPLAY 1.021277 (12825 2850);
PAINT ORANGE (12825 2850);
DISPLAY INVISIBLE (12825 2850);
FORCEADD OFFPAGE..4
(12525 2700);
FORCEPROP 2 LAST $XR0 90 
J 0
(12711 2700);
DISPLAY 0.638298 (12711 2700);
PAINT MONO (12711 2700);
FORCEPROP 2 LAST CDS_LIB mstr_standard
J 0
(12525 2700);
PAINT MONO (12525 2700);
DISPLAY INVISIBLE (12525 2700);
FORCEPROP 1 LAST OFFPAGE TRUE
J 0
(12850 2575);
DISPLAY 1.170213 (12850 2575);
PAINT GREEN (12850 2575);
DISPLAY INVISIBLE (12850 2575);
FORCEPROP 1 LAST COMMENT_BODY TRUE
J 0
(12500 2600);
DISPLAY 1.170213 (12500 2600);
PAINT GREEN (12500 2600);
DISPLAY INVISIBLE (12500 2600);
FORCEPROP 2 LAST PATH I38
J 0
(12700 2775);
DISPLAY 1.021277 (12700 2775);
PAINT ORANGE (12700 2775);
DISPLAY INVISIBLE (12700 2775);
FORCEADD OFFPAGE..4
(12525 2600);
FORCEPROP 2 LAST $XR0 90 
J 0
(12711 2600);
DISPLAY 0.638298 (12711 2600);
PAINT MONO (12711 2600);
FORCEPROP 2 LAST $XR1 156 
J 0
(12801 2600);
DISPLAY 0.638298 (12801 2600);
PAINT MONO (12801 2600);
FORCEPROP 2 LAST CDS_LIB mstr_standard
J 0
(12525 2600);
PAINT MONO (12525 2600);
DISPLAY INVISIBLE (12525 2600);
FORCEPROP 1 LAST OFFPAGE TRUE
J 0
(12850 2475);
DISPLAY 1.170213 (12850 2475);
PAINT GREEN (12850 2475);
DISPLAY INVISIBLE (12850 2475);
FORCEPROP 1 LAST COMMENT_BODY TRUE
J 0
(12500 2500);
DISPLAY 1.170213 (12500 2500);
PAINT GREEN (12500 2500);
DISPLAY INVISIBLE (12500 2500);
FORCEPROP 2 LAST PATH I39
J 0
(12725 2650);
DISPLAY 1.021277 (12725 2650);
PAINT ORANGE (12725 2650);
DISPLAY INVISIBLE (12725 2650);
FORCEADD RES..2
(13575 3925);
FORCEPROP 1 LAST LOCATION R9N1
J 0
(13620 4050);
DISPLAY 0.617021 (13620 4050);
PAINT AQUA (13620 4050);
FORCEPROP 1 LAST PART_NUMBER G21796-047
R 1
J 0
(13640 3725);
DISPLAY 0.617021 (13640 3725);
PAINT BLUE (13640 3725);
FORCEPROP 1 LAST VALUE 49.9
R 1
J 0
(13695 3900);
DISPLAY 0.617021 (13695 3900);
PAINT SKYBLUE (13695 3900);
FORCEPROP 1 LAST MATERIAL CHIP
R 1
J 0
(13690 3725);
DISPLAY 0.617021 (13690 3725);
PAINT SKYBLUE (13690 3725);
FORCEPROP 1 LASTPIN (13575 3825) $PN 2
J 0
(13580 3835);
DISPLAY 0.617021 (13580 3835);
PAINT GREEN (13580 3835);
FORCEPROP 1 LASTPIN (13575 4025) $PN 1
J 0
(13580 3987);
DISPLAY 0.617021 (13580 3987);
PAINT GREEN (13580 3987);
FORCEPROP 1 LAST TOLERANCE 1%
J 0
(13620 3950);
DISPLAY 0.978723 (13620 3950);
PAINT SKYBLUE (13620 3950);
DISPLAY INVISIBLE (13620 3950);
FORCEPROP 1 LAST PACK_TYPE 0402
J 0
(13615 3750);
DISPLAY 0.978723 (13615 3750);
PAINT SKYBLUE (13615 3750);
DISPLAY INVISIBLE (13615 3750);
FORCEPROP 1 LAST WATTAGE 1/16W
J 0
(13615 3900);
DISPLAY 0.978723 (13615 3900);
PAINT SKYBLUE (13615 3900);
DISPLAY INVISIBLE (13615 3900);
FORCEPROP 2 LAST CDS_LIB mstr_discrete
J 0
(13575 3925);
PAINT ORANGE (13575 3925);
DISPLAY INVISIBLE (13575 3925);
FORCEPROP 2 LAST SEC_TYPE 0402
J 0
(13625 4150);
DISPLAY 1.021277 (13625 4150);
PAINT ORANGE (13625 4150);
DISPLAY INVISIBLE (13625 4150);
FORCEPROP 2 LAST BOM_COST PROC_SOCKET
J 0
(13625 4150);
PAINT MONO (13625 4150);
DISPLAY INVISIBLE (13625 4150);
FORCEPROP 2 LAST SEC 1
J 0
(13625 4150);
DISPLAY 0.680851 (13625 4150);
PAINT MONO (13625 4150);
DISPLAY INVISIBLE (13625 4150);
FORCEPROP 2 LAST CDS_LOCATION R9N1
J 0
(13620 4050);
DISPLAY 0.617021 (13620 4050);
PAINT AQUA (13620 4050);
DISPLAY INVISIBLE (13620 4050);
FORCEPROP 1 LAST PATH I4
J 0
(13625 4100);
DISPLAY 0.978723 (13625 4100);
PAINT WHITE (13625 4100);
DISPLAY INVISIBLE (13625 4100);
FORCEPROP 2 LAST ROOM CPU1
J 0
(13625 4100);
PAINT MONO (13625 4100);
DISPLAY INVISIBLE (13625 4100);
FORCEADD OFFPAGE..4
(12525 2650);
FORCEPROP 2 LAST $XR0 90 
J 0
(12711 2650);
DISPLAY 0.638298 (12711 2650);
PAINT MONO (12711 2650);
FORCEPROP 2 LAST CDS_LIB mstr_standard
J 0
(12525 2650);
PAINT MONO (12525 2650);
DISPLAY INVISIBLE (12525 2650);
FORCEPROP 1 LAST OFFPAGE TRUE
J 0
(12850 2525);
DISPLAY 1.170213 (12850 2525);
PAINT GREEN (12850 2525);
DISPLAY INVISIBLE (12850 2525);
FORCEPROP 1 LAST COMMENT_BODY TRUE
J 0
(12500 2550);
DISPLAY 1.170213 (12500 2550);
PAINT GREEN (12500 2550);
DISPLAY INVISIBLE (12500 2550);
FORCEPROP 2 LAST PATH I40
J 0
(12700 2725);
DISPLAY 1.021277 (12700 2725);
PAINT ORANGE (12700 2725);
DISPLAY INVISIBLE (12700 2725);
FORCEADD OFFPAGE..4
(12525 2500);
FORCEPROP 2 LAST $XR0 90 
J 0
(12711 2500);
DISPLAY 0.638298 (12711 2500);
PAINT MONO (12711 2500);
FORCEPROP 2 LAST CDS_LIB mstr_standard
J 0
(12525 2500);
PAINT MONO (12525 2500);
DISPLAY INVISIBLE (12525 2500);
FORCEPROP 1 LAST OFFPAGE TRUE
J 0
(12850 2375);
DISPLAY 1.170213 (12850 2375);
PAINT GREEN (12850 2375);
DISPLAY INVISIBLE (12850 2375);
FORCEPROP 1 LAST COMMENT_BODY TRUE
J 0
(12500 2400);
DISPLAY 1.170213 (12500 2400);
PAINT GREEN (12500 2400);
DISPLAY INVISIBLE (12500 2400);
FORCEPROP 2 LAST PATH I41
J 0
(12700 2575);
DISPLAY 1.021277 (12700 2575);
PAINT ORANGE (12700 2575);
DISPLAY INVISIBLE (12700 2575);
FORCEADD OFFPAGE..4
(12525 2550);
FORCEPROP 2 LAST $XR0 90 
J 0
(12711 2550);
DISPLAY 0.638298 (12711 2550);
PAINT MONO (12711 2550);
FORCEPROP 2 LAST CDS_LIB mstr_standard
J 0
(12525 2550);
PAINT MONO (12525 2550);
DISPLAY INVISIBLE (12525 2550);
FORCEPROP 1 LAST OFFPAGE TRUE
J 0
(12850 2425);
DISPLAY 1.170213 (12850 2425);
PAINT GREEN (12850 2425);
DISPLAY INVISIBLE (12850 2425);
FORCEPROP 1 LAST COMMENT_BODY TRUE
J 0
(12500 2450);
DISPLAY 1.170213 (12500 2450);
PAINT GREEN (12500 2450);
DISPLAY INVISIBLE (12500 2450);
FORCEPROP 2 LAST PATH I42
J 0
(12700 2625);
DISPLAY 1.021277 (12700 2625);
PAINT ORANGE (12700 2625);
DISPLAY INVISIBLE (12700 2625);
FORCEADD OFFPAGE..3
(12500 2400);
FORCEPROP 2 LAST $XR0 97 
J 0
(12714 2400);
DISPLAY 0.638298 (12714 2400);
PAINT MONO (12714 2400);
FORCEPROP 2 LAST CDS_LIB mstr_standard
J 0
(12500 2400);
PAINT MONO (12500 2400);
DISPLAY INVISIBLE (12500 2400);
FORCEPROP 1 LAST OFFPAGE TRUE
J 0
(12825 2275);
DISPLAY 1.170213 (12825 2275);
PAINT GREEN (12825 2275);
DISPLAY INVISIBLE (12825 2275);
FORCEPROP 1 LAST COMMENT_BODY TRUE
J 0
(12450 2300);
DISPLAY 1.170213 (12450 2300);
PAINT GREEN (12450 2300);
DISPLAY INVISIBLE (12450 2300);
FORCEPROP 2 LAST PATH I43
J 0
(12700 2475);
DISPLAY 1.021277 (12700 2475);
PAINT ORANGE (12700 2475);
DISPLAY INVISIBLE (12700 2475);
FORCEADD OFFPAGE..4
(12525 2450);
FORCEPROP 2 LAST $XR0 90 
J 0
(12711 2450);
DISPLAY 0.638298 (12711 2450);
PAINT MONO (12711 2450);
FORCEPROP 2 LAST CDS_LIB mstr_standard
J 0
(12525 2450);
PAINT MONO (12525 2450);
DISPLAY INVISIBLE (12525 2450);
FORCEPROP 1 LAST OFFPAGE TRUE
J 0
(12850 2325);
DISPLAY 1.170213 (12850 2325);
PAINT GREEN (12850 2325);
DISPLAY INVISIBLE (12850 2325);
FORCEPROP 1 LAST COMMENT_BODY TRUE
J 0
(12500 2350);
DISPLAY 1.170213 (12500 2350);
PAINT GREEN (12500 2350);
DISPLAY INVISIBLE (12500 2350);
FORCEPROP 2 LAST PATH I44
J 0
(12700 2525);
DISPLAY 1.021277 (12700 2525);
PAINT ORANGE (12700 2525);
DISPLAY INVISIBLE (12700 2525);
FORCEADD OFFPAGE..2
(12575 800);
FORCEPROP 2 LAST $XR0 112 
J 0
(12764 800);
DISPLAY 0.638298 (12764 800);
PAINT MONO (12764 800);
FORCEPROP 2 LAST CDS_LIB mstr_standard
J 0
(12575 800);
PAINT MONO (12575 800);
DISPLAY INVISIBLE (12575 800);
FORCEPROP 1 LAST OFFPAGE TRUE
J 0
(12900 675);
DISPLAY 1.170213 (12900 675);
PAINT GREEN (12900 675);
DISPLAY INVISIBLE (12900 675);
FORCEPROP 1 LAST COMMENT_BODY TRUE
J 0
(12530 705);
DISPLAY 1.170213 (12530 705);
PAINT GREEN (12530 705);
DISPLAY INVISIBLE (12530 705);
FORCEPROP 2 LAST PATH I57
J 0
(12750 875);
DISPLAY 1.021277 (12750 875);
PAINT ORANGE (12750 875);
DISPLAY INVISIBLE (12750 875);
FORCEADD OFFPAGE..1
(7975 4150);
FORCEPROP 2 LAST $XR0 103 
J 0
(7723 4150);
DISPLAY 0.638298 (7723 4150);
PAINT MONO (7723 4150);
FORCEPROP 2 LAST CDS_LIB mstr_standard
J 0
(7975 4150);
PAINT MONO (7975 4150);
DISPLAY INVISIBLE (7975 4150);
FORCEPROP 1 LAST OFFPAGE TRUE
J 0
(8300 4025);
DISPLAY 1.170213 (8300 4025);
PAINT GREEN (8300 4025);
DISPLAY INVISIBLE (8300 4025);
FORCEPROP 1 LAST COMMENT_BODY TRUE
J 0
(8100 4050);
DISPLAY 1.170213 (8100 4050);
PAINT GREEN (8100 4050);
DISPLAY INVISIBLE (8100 4050);
FORCEPROP 2 LAST PATH I58
J 0
(7725 4200);
DISPLAY 1.021277 (7725 4200);
PAINT ORANGE (7725 4200);
DISPLAY INVISIBLE (7725 4200);
FORCEADD OFFPAGE..1
(7975 4100);
FORCEPROP 2 LAST $XR0 103 
J 0
(7723 4100);
DISPLAY 0.638298 (7723 4100);
PAINT MONO (7723 4100);
FORCEPROP 2 LAST CDS_LIB mstr_standard
J 0
(7975 4100);
PAINT MONO (7975 4100);
DISPLAY INVISIBLE (7975 4100);
FORCEPROP 1 LAST OFFPAGE TRUE
J 0
(8300 3975);
DISPLAY 1.170213 (8300 3975);
PAINT GREEN (8300 3975);
DISPLAY INVISIBLE (8300 3975);
FORCEPROP 1 LAST COMMENT_BODY TRUE
J 0
(8100 4000);
DISPLAY 1.170213 (8100 4000);
PAINT GREEN (8100 4000);
DISPLAY INVISIBLE (8100 4000);
FORCEPROP 2 LAST PATH I59
J 0
(7725 4150);
DISPLAY 1.021277 (7725 4150);
PAINT ORANGE (7725 4150);
DISPLAY INVISIBLE (7725 4150);
FORCEADD PVCCIO_CPU1..1
(13325 4275);
FORCEPROP 3 LASTPIN (13325 4225) SIG_NAME PVCCIO_CPU1\g
J 0
(13335 4235);
DISPLAY 0.659574 (13335 4235);
PAINT MONO (13335 4235);
DISPLAY INVISIBLE (13335 4235);
FORCEPROP 1 LAST VOLTAGE 1.1V
J 0
(13280 4232);
DISPLAY 0.340426 (13280 4232);
PAINT SKYBLUE (13280 4232);
DISPLAY INVISIBLE (13280 4232);
FORCEPROP 2 LAST CDS_LIB mstr_symbols
J 0
(13325 4275);
PAINT ORANGE (13325 4275);
DISPLAY INVISIBLE (13325 4275);
FORCEPROP 1 LAST BODY_TYPE PLUMBING
J 0
(13280 4232);
DISPLAY 0.340426 (13280 4232);
PAINT GREEN (13280 4232);
DISPLAY INVISIBLE (13280 4232);
FORCEPROP 1 LAST PATH I6
J 0
(13375 4300);
DISPLAY 0.872340 (13375 4300);
PAINT AQUA (13375 4300);
DISPLAY INVISIBLE (13375 4300);
FORCEPROP 1 LAST HDL_POWER PVCCIO_CPU1
J 1
(13325 4325);
DISPLAY 0.872340 (13325 4325);
PAINT GREEN (13325 4325);
DISPLAY INVISIBLE (13325 4325);
FORCEADD OFFPAGE..1
(7975 3950);
FORCEPROP 2 LAST $XR0 103 
J 0
(7723 3950);
DISPLAY 0.638298 (7723 3950);
PAINT MONO (7723 3950);
FORCEPROP 2 LAST CDS_LIB mstr_standard
J 0
(7975 3950);
PAINT MONO (7975 3950);
DISPLAY INVISIBLE (7975 3950);
FORCEPROP 1 LAST OFFPAGE TRUE
J 0
(8300 3825);
DISPLAY 1.170213 (8300 3825);
PAINT GREEN (8300 3825);
DISPLAY INVISIBLE (8300 3825);
FORCEPROP 1 LAST COMMENT_BODY TRUE
J 0
(8100 3850);
DISPLAY 1.170213 (8100 3850);
PAINT GREEN (8100 3850);
DISPLAY INVISIBLE (8100 3850);
FORCEPROP 2 LAST PATH I60
J 0
(7725 4000);
DISPLAY 1.021277 (7725 4000);
PAINT ORANGE (7725 4000);
DISPLAY INVISIBLE (7725 4000);
FORCEADD OFFPAGE..1
(7975 4000);
FORCEPROP 2 LAST $XR0 103 
J 0
(7723 4000);
DISPLAY 0.638298 (7723 4000);
PAINT MONO (7723 4000);
FORCEPROP 2 LAST CDS_LIB mstr_standard
J 0
(7975 4000);
PAINT MONO (7975 4000);
DISPLAY INVISIBLE (7975 4000);
FORCEPROP 1 LAST OFFPAGE TRUE
J 0
(8300 3875);
DISPLAY 1.170213 (8300 3875);
PAINT GREEN (8300 3875);
DISPLAY INVISIBLE (8300 3875);
FORCEPROP 1 LAST COMMENT_BODY TRUE
J 0
(8100 3900);
DISPLAY 1.170213 (8100 3900);
PAINT GREEN (8100 3900);
DISPLAY INVISIBLE (8100 3900);
FORCEPROP 2 LAST PATH I61
J 0
(7725 4050);
DISPLAY 1.021277 (7725 4050);
PAINT ORANGE (7725 4050);
DISPLAY INVISIBLE (7725 4050);
FORCEADD OFFPAGE..1
(7975 3700);
FORCEPROP 2 LAST $XR0 96 
J 0
(7754 3700);
DISPLAY 0.638298 (7754 3700);
PAINT MONO (7754 3700);
FORCEPROP 2 LAST CDS_LIB mstr_standard
J 0
(7975 3700);
PAINT MONO (7975 3700);
DISPLAY INVISIBLE (7975 3700);
FORCEPROP 1 LAST OFFPAGE TRUE
J 0
(8300 3575);
DISPLAY 1.170213 (8300 3575);
PAINT GREEN (8300 3575);
DISPLAY INVISIBLE (8300 3575);
FORCEPROP 1 LAST COMMENT_BODY TRUE
J 0
(8100 3600);
DISPLAY 1.170213 (8100 3600);
PAINT GREEN (8100 3600);
DISPLAY INVISIBLE (8100 3600);
FORCEPROP 2 LAST PATH I62
J 0
(8025 3775);
DISPLAY 1.021277 (8025 3775);
PAINT ORANGE (8025 3775);
DISPLAY INVISIBLE (8025 3775);
FORCEADD OFFPAGE..1
(7975 3650);
FORCEPROP 2 LAST $XR0 96 
J 0
(7754 3650);
DISPLAY 0.638298 (7754 3650);
PAINT MONO (7754 3650);
FORCEPROP 2 LAST CDS_LIB mstr_standard
J 0
(7975 3650);
PAINT MONO (7975 3650);
DISPLAY INVISIBLE (7975 3650);
FORCEPROP 1 LAST OFFPAGE TRUE
J 0
(8300 3525);
DISPLAY 1.170213 (8300 3525);
PAINT GREEN (8300 3525);
DISPLAY INVISIBLE (8300 3525);
FORCEPROP 1 LAST COMMENT_BODY TRUE
J 0
(8100 3550);
DISPLAY 1.170213 (8100 3550);
PAINT GREEN (8100 3550);
DISPLAY INVISIBLE (8100 3550);
FORCEPROP 2 LAST PATH I63
J 0
(8025 3725);
DISPLAY 1.021277 (8025 3725);
PAINT ORANGE (8025 3725);
DISPLAY INVISIBLE (8025 3725);
FORCEADD OFFPAGE..5
(7950 3500);
FORCEPROP 2 LAST $XR0 83 
J 0
(7726 3500);
DISPLAY 0.638298 (7726 3500);
PAINT MONO (7726 3500);
FORCEPROP 2 LAST $XR1 84 
J 0
(7636 3500);
DISPLAY 0.638298 (7636 3500);
PAINT MONO (7636 3500);
FORCEPROP 2 LAST $XR2 85 
J 0
(7546 3500);
DISPLAY 0.638298 (7546 3500);
PAINT MONO (7546 3500);
FORCEPROP 2 LAST $XR3 86 
J 0
(7456 3500);
DISPLAY 0.638298 (7456 3500);
PAINT MONO (7456 3500);
FORCEPROP 2 LAST $XR4 87 
J 0
(7366 3500);
DISPLAY 0.638298 (7366 3500);
PAINT MONO (7366 3500);
FORCEPROP 2 LAST $XR5 88 
J 0
(7276 3500);
DISPLAY 0.638298 (7276 3500);
PAINT MONO (7276 3500);
FORCEPROP 2 LAST CDS_LIB mstr_standard
J 0
(7950 3500);
PAINT MONO (7950 3500);
DISPLAY INVISIBLE (7950 3500);
FORCEPROP 1 LAST OFFPAGE TRUE
J 0
(8275 3375);
DISPLAY 1.170213 (8275 3375);
PAINT GREEN (8275 3375);
DISPLAY INVISIBLE (8275 3375);
FORCEPROP 1 LAST COMMENT_BODY TRUE
J 0
(8050 3425);
DISPLAY 1.170213 (8050 3425);
PAINT GREEN (8050 3425);
DISPLAY INVISIBLE (8050 3425);
FORCEPROP 2 LAST PATH I64
J 0
(8000 3575);
DISPLAY 1.021277 (8000 3575);
PAINT ORANGE (8000 3575);
DISPLAY INVISIBLE (8000 3575);
FORCEADD OFFPAGE..5
(7950 3550);
FORCEPROP 2 LAST $XR0 77 
J 0
(7726 3550);
DISPLAY 0.638298 (7726 3550);
PAINT MONO (7726 3550);
FORCEPROP 2 LAST $XR1 78 
J 0
(7636 3550);
DISPLAY 0.638298 (7636 3550);
PAINT MONO (7636 3550);
FORCEPROP 2 LAST $XR2 79 
J 0
(7546 3550);
DISPLAY 0.638298 (7546 3550);
PAINT MONO (7546 3550);
FORCEPROP 2 LAST $XR3 80 
J 0
(7456 3550);
DISPLAY 0.638298 (7456 3550);
PAINT MONO (7456 3550);
FORCEPROP 2 LAST $XR4 81 
J 0
(7366 3550);
DISPLAY 0.638298 (7366 3550);
PAINT MONO (7366 3550);
FORCEPROP 2 LAST $XR5 82 
J 0
(7276 3550);
DISPLAY 0.638298 (7276 3550);
PAINT MONO (7276 3550);
FORCEPROP 2 LAST CDS_LIB mstr_standard
J 0
(7950 3550);
PAINT MONO (7950 3550);
DISPLAY INVISIBLE (7950 3550);
FORCEPROP 1 LAST OFFPAGE TRUE
J 0
(8275 3425);
DISPLAY 1.170213 (8275 3425);
PAINT GREEN (8275 3425);
DISPLAY INVISIBLE (8275 3425);
FORCEPROP 1 LAST COMMENT_BODY TRUE
J 0
(8050 3475);
DISPLAY 1.170213 (8050 3475);
PAINT GREEN (8050 3475);
DISPLAY INVISIBLE (8050 3475);
FORCEPROP 2 LAST PATH I65
J 0
(8000 3625);
DISPLAY 1.021277 (8000 3625);
PAINT ORANGE (8000 3625);
DISPLAY INVISIBLE (8000 3625);
FORCEADD OFFPAGE..6
(7975 3400);
FORCEPROP 2 LAST $XR0 94 
J 0
(7726 3400);
DISPLAY 0.638298 (7726 3400);
PAINT MONO (7726 3400);
FORCEPROP 2 LAST $XR1 95 
J 0
(7636 3400);
DISPLAY 0.638298 (7636 3400);
PAINT MONO (7636 3400);
FORCEPROP 2 LAST $XR2 152 
J 0
(7516 3400);
DISPLAY 0.638298 (7516 3400);
PAINT MONO (7516 3400);
FORCEPROP 2 LAST CDS_LIB mstr_standard
J 0
(7975 3400);
PAINT MONO (7975 3400);
DISPLAY INVISIBLE (7975 3400);
FORCEPROP 1 LAST OFFPAGE TRUE
J 0
(8300 3275);
DISPLAY 1.170213 (8300 3275);
PAINT GREEN (8300 3275);
DISPLAY INVISIBLE (8300 3275);
FORCEPROP 1 LAST COMMENT_BODY TRUE
J 0
(8075 3325);
DISPLAY 1.170213 (8075 3325);
PAINT GREEN (8075 3325);
DISPLAY INVISIBLE (8075 3325);
FORCEPROP 2 LAST PATH I67
J 0
(8025 3475);
DISPLAY 1.021277 (8025 3475);
PAINT ORANGE (8025 3475);
DISPLAY INVISIBLE (8025 3475);
FORCEADD OFFPAGE..6
(7975 3350);
FORCEPROP 2 LAST $XR0 94 
J 0
(7726 3350);
DISPLAY 0.638298 (7726 3350);
PAINT MONO (7726 3350);
FORCEPROP 2 LAST $XR1 95 
J 0
(7636 3350);
DISPLAY 0.638298 (7636 3350);
PAINT MONO (7636 3350);
FORCEPROP 2 LAST $XR2 152 
J 0
(7516 3350);
DISPLAY 0.638298 (7516 3350);
PAINT MONO (7516 3350);
FORCEPROP 2 LAST CDS_LIB mstr_standard
J 0
(7975 3350);
PAINT MONO (7975 3350);
DISPLAY INVISIBLE (7975 3350);
FORCEPROP 1 LAST OFFPAGE TRUE
J 0
(8300 3225);
DISPLAY 1.170213 (8300 3225);
PAINT GREEN (8300 3225);
DISPLAY INVISIBLE (8300 3225);
FORCEPROP 1 LAST COMMENT_BODY TRUE
J 0
(8075 3275);
DISPLAY 1.170213 (8075 3275);
PAINT GREEN (8075 3275);
DISPLAY INVISIBLE (8075 3275);
FORCEPROP 2 LAST PATH I68
J 0
(8025 3425);
DISPLAY 1.021277 (8025 3425);
PAINT ORANGE (8025 3425);
DISPLAY INVISIBLE (8025 3425);
FORCEADD RES..2
(13325 3925);
FORCEPROP 1 LAST LOCATION R9N2
J 0
(13370 4050);
DISPLAY 0.617021 (13370 4050);
PAINT AQUA (13370 4050);
FORCEPROP 1 LAST PART_NUMBER G21796-017
R 1
J 0
(13390 3725);
DISPLAY 0.617021 (13390 3725);
PAINT BLUE (13390 3725);
FORCEPROP 1 LAST VALUE 100.0
R 1
J 0
(13445 3900);
DISPLAY 0.617021 (13445 3900);
PAINT SKYBLUE (13445 3900);
FORCEPROP 1 LAST MATERIAL CHIP
R 1
J 0
(13440 3725);
DISPLAY 0.617021 (13440 3725);
PAINT SKYBLUE (13440 3725);
FORCEPROP 1 LASTPIN (13325 3825) $PN 2
J 0
(13330 3835);
DISPLAY 0.617021 (13330 3835);
PAINT GREEN (13330 3835);
FORCEPROP 1 LASTPIN (13325 4025) $PN 1
J 0
(13330 3987);
DISPLAY 0.617021 (13330 3987);
PAINT GREEN (13330 3987);
FORCEPROP 1 LAST TOLERANCE 1%
J 0
(13370 3950);
DISPLAY 0.978723 (13370 3950);
PAINT SKYBLUE (13370 3950);
DISPLAY INVISIBLE (13370 3950);
FORCEPROP 1 LAST PACK_TYPE 0402
J 0
(13365 3750);
DISPLAY 0.978723 (13365 3750);
PAINT SKYBLUE (13365 3750);
DISPLAY INVISIBLE (13365 3750);
FORCEPROP 1 LAST WATTAGE 1/16W
J 0
(13365 3900);
DISPLAY 0.978723 (13365 3900);
PAINT SKYBLUE (13365 3900);
DISPLAY INVISIBLE (13365 3900);
FORCEPROP 2 LAST SEC_TYPE 0402
J 0
(13375 4150);
DISPLAY 1.021277 (13375 4150);
PAINT ORANGE (13375 4150);
DISPLAY INVISIBLE (13375 4150);
FORCEPROP 2 LAST CDS_LIB mstr_discrete
J 0
(13325 3925);
PAINT ORANGE (13325 3925);
DISPLAY INVISIBLE (13325 3925);
FORCEPROP 2 LAST BOM_COST PROC_SOCKET
J 0
(13375 4150);
PAINT MONO (13375 4150);
DISPLAY INVISIBLE (13375 4150);
FORCEPROP 2 LAST SEC 1
J 0
(13375 4150);
DISPLAY 0.680851 (13375 4150);
PAINT MONO (13375 4150);
DISPLAY INVISIBLE (13375 4150);
FORCEPROP 2 LAST CDS_LOCATION R9N2
J 0
(13370 4050);
DISPLAY 0.617021 (13370 4050);
PAINT AQUA (13370 4050);
DISPLAY INVISIBLE (13370 4050);
FORCEPROP 1 LAST PATH I7
J 0
(13375 4100);
DISPLAY 0.978723 (13375 4100);
PAINT WHITE (13375 4100);
DISPLAY INVISIBLE (13375 4100);
FORCEPROP 2 LAST ROOM CPU1
J 0
(13375 4100);
PAINT MONO (13375 4100);
DISPLAY INVISIBLE (13375 4100);
FORCEADD OFFPAGE..5
(7950 3150);
FORCEPROP 2 LAST $XR0 100 
J 0
(7695 3150);
DISPLAY 0.638298 (7695 3150);
PAINT MONO (7695 3150);
FORCEPROP 2 LAST CDS_LIB mstr_standard
J 0
(7950 3150);
PAINT MONO (7950 3150);
DISPLAY INVISIBLE (7950 3150);
FORCEPROP 1 LAST OFFPAGE TRUE
J 0
(8275 3025);
DISPLAY 1.170213 (8275 3025);
PAINT GREEN (8275 3025);
DISPLAY INVISIBLE (8275 3025);
FORCEPROP 1 LAST COMMENT_BODY TRUE
J 0
(8050 3075);
DISPLAY 1.170213 (8050 3075);
PAINT GREEN (8050 3075);
DISPLAY INVISIBLE (8050 3075);
FORCEPROP 2 LAST PATH I70
J 0
(8000 3225);
DISPLAY 1.021277 (8000 3225);
PAINT ORANGE (8000 3225);
DISPLAY INVISIBLE (8000 3225);
FORCEADD OFFPAGE..5
(7950 3000);
FORCEPROP 2 LAST $XR0 100 
J 0
(7695 3000);
DISPLAY 0.638298 (7695 3000);
PAINT MONO (7695 3000);
FORCEPROP 2 LAST CDS_LIB mstr_standard
J 0
(7950 3000);
PAINT MONO (7950 3000);
DISPLAY INVISIBLE (7950 3000);
FORCEPROP 1 LAST OFFPAGE TRUE
J 0
(8275 2875);
DISPLAY 1.170213 (8275 2875);
PAINT GREEN (8275 2875);
DISPLAY INVISIBLE (8275 2875);
FORCEPROP 1 LAST COMMENT_BODY TRUE
J 0
(8050 2925);
DISPLAY 1.170213 (8050 2925);
PAINT GREEN (8050 2925);
DISPLAY INVISIBLE (8050 2925);
FORCEPROP 2 LAST PATH I73
J 0
(8000 3075);
DISPLAY 1.021277 (8000 3075);
PAINT ORANGE (8000 3075);
DISPLAY INVISIBLE (8000 3075);
FORCEADD OFFPAGE..4
(12525 4150);
FORCEPROP 2 LAST $XR0 96 
J 0
(12711 4150);
DISPLAY 0.638298 (12711 4150);
PAINT MONO (12711 4150);
FORCEPROP 2 LAST CDS_LIB mstr_standard
J 0
(12525 4150);
PAINT MONO (12525 4150);
DISPLAY INVISIBLE (12525 4150);
FORCEPROP 1 LAST OFFPAGE TRUE
J 0
(12850 4025);
DISPLAY 1.170213 (12850 4025);
PAINT GREEN (12850 4025);
DISPLAY INVISIBLE (12850 4025);
FORCEPROP 1 LAST COMMENT_BODY TRUE
J 0
(12500 4050);
DISPLAY 1.170213 (12500 4050);
PAINT GREEN (12500 4050);
DISPLAY INVISIBLE (12500 4050);
FORCEPROP 2 LAST PATH I8
J 0
(12825 4200);
DISPLAY 1.021277 (12825 4200);
PAINT ORANGE (12825 4200);
DISPLAY INVISIBLE (12825 4200);
FORCEADD OFFPAGE..5
(8225 2550);
FORCEPROP 2 LAST $XR0 99 
J 0
(8001 2550);
DISPLAY 0.638298 (8001 2550);
PAINT MONO (8001 2550);
FORCEPROP 2 LAST CDS_LIB mstr_standard
J 0
(8225 2550);
PAINT MONO (8225 2550);
DISPLAY INVISIBLE (8225 2550);
FORCEPROP 1 LAST OFFPAGE TRUE
J 0
(8550 2425);
DISPLAY 1.170213 (8550 2425);
PAINT GREEN (8550 2425);
DISPLAY INVISIBLE (8550 2425);
FORCEPROP 1 LAST COMMENT_BODY TRUE
J 0
(8325 2475);
DISPLAY 1.170213 (8325 2475);
PAINT GREEN (8325 2475);
DISPLAY INVISIBLE (8325 2475);
FORCEPROP 2 LAST PATH I80
J 0
(8275 2625);
DISPLAY 1.021277 (8275 2625);
PAINT ORANGE (8275 2625);
DISPLAY INVISIBLE (8275 2625);
FORCEADD OFFPAGE..5
(8225 2500);
FORCEPROP 2 LAST $XR0 99 
J 0
(8001 2500);
DISPLAY 0.638298 (8001 2500);
PAINT MONO (8001 2500);
FORCEPROP 2 LAST CDS_LIB mstr_standard
J 0
(8225 2500);
PAINT MONO (8225 2500);
DISPLAY INVISIBLE (8225 2500);
FORCEPROP 1 LAST OFFPAGE TRUE
J 0
(8550 2375);
DISPLAY 1.170213 (8550 2375);
PAINT GREEN (8550 2375);
DISPLAY INVISIBLE (8550 2375);
FORCEPROP 1 LAST COMMENT_BODY TRUE
J 0
(8325 2425);
DISPLAY 1.170213 (8325 2425);
PAINT GREEN (8325 2425);
DISPLAY INVISIBLE (8325 2425);
FORCEPROP 2 LAST PATH I81
J 0
(8275 2575);
DISPLAY 1.021277 (8275 2575);
PAINT ORANGE (8275 2575);
DISPLAY INVISIBLE (8275 2575);
FORCEADD OFFPAGE..5
(8225 2450);
FORCEPROP 2 LAST $XR0 99 
J 0
(8001 2450);
DISPLAY 0.638298 (8001 2450);
PAINT MONO (8001 2450);
FORCEPROP 2 LAST CDS_LIB mstr_standard
J 0
(8225 2450);
PAINT MONO (8225 2450);
DISPLAY INVISIBLE (8225 2450);
FORCEPROP 1 LAST OFFPAGE TRUE
J 0
(8550 2325);
DISPLAY 1.170213 (8550 2325);
PAINT GREEN (8550 2325);
DISPLAY INVISIBLE (8550 2325);
FORCEPROP 1 LAST COMMENT_BODY TRUE
J 0
(8325 2375);
DISPLAY 1.170213 (8325 2375);
PAINT GREEN (8325 2375);
DISPLAY INVISIBLE (8325 2375);
FORCEPROP 2 LAST PATH I82
J 0
(8275 2525);
DISPLAY 1.021277 (8275 2525);
PAINT ORANGE (8275 2525);
DISPLAY INVISIBLE (8275 2525);
FORCEADD OFFPAGE..5
(8225 2400);
FORCEPROP 2 LAST $XR0 99 
J 0
(8001 2400);
DISPLAY 0.638298 (8001 2400);
PAINT MONO (8001 2400);
FORCEPROP 2 LAST CDS_LIB mstr_standard
J 0
(8225 2400);
PAINT MONO (8225 2400);
DISPLAY INVISIBLE (8225 2400);
FORCEPROP 1 LAST OFFPAGE TRUE
J 0
(8550 2275);
DISPLAY 1.170213 (8550 2275);
PAINT GREEN (8550 2275);
DISPLAY INVISIBLE (8550 2275);
FORCEPROP 1 LAST COMMENT_BODY TRUE
J 0
(8325 2325);
DISPLAY 1.170213 (8325 2325);
PAINT GREEN (8325 2325);
DISPLAY INVISIBLE (8325 2325);
FORCEPROP 2 LAST PATH I83
J 0
(8275 2475);
DISPLAY 1.021277 (8275 2475);
PAINT ORANGE (8275 2475);
DISPLAY INVISIBLE (8275 2475);
FORCEADD DESIGN_NOTE..1
(9650 525);
FORCEPROP 0 LAST L1 CPU SYMBOLS 1-30 ARE PRELIMINARY AND SUBJECT TO CHANGE
J 0
(9450 400);
DISPLAY 1.021277 (9450 400);
PAINT ORANGE (9450 400);
FORCEPROP 2 LAST CDS_LIB mstr_symbols
J 0
(9650 525);
PAINT ORANGE (9650 525);
DISPLAY INVISIBLE (9650 525);
FORCEPROP 1 LAST COMMENT_BODY TRUE
J 0
(9675 625);
DISPLAY 0.978723 (9675 625);
PAINT ORANGE (9675 625);
DISPLAY INVISIBLE (9675 625);
FORCEADD DESIGN_NOTE..1
(13300 1675);
FORCEPROP 0 LAST L1 CPU1 PIROM ADDRESS: 0XA2
J 0
(13100 1550);
DISPLAY 1.021277 (13100 1550);
PAINT ORANGE (13100 1550);
FORCEPROP 2 LAST CDS_LIB mstr_symbols
J 0
(13300 1675);
PAINT ORANGE (13300 1675);
DISPLAY INVISIBLE (13300 1675);
FORCEPROP 1 LAST COMMENT_BODY TRUE
J 0
(13325 1775);
DISPLAY 0.978723 (13325 1775);
PAINT ORANGE (13325 1775);
DISPLAY INVISIBLE (13325 1775);
FORCEADD CAD_NOTE..1
(6575 850);
FORCEPROP 0 LAST LINE2 WITHIN 1.1 OF CPU PINS
J 0
(6425 650);
PAINT WHITE (6425 650);
FORCEPROP 0 LAST LINE PLACE RBIAS RESISTORS
J 0
(6425 725);
PAINT WHITE (6425 725);
FORCEPROP 2 LAST CDS_LIB mstr_symbols
J 0
(6575 850);
PAINT ORANGE (6575 850);
DISPLAY INVISIBLE (6575 850);
FORCEPROP 1 LAST COMMENT_BODY TRUE
J 0
(6600 950);
DISPLAY 1.340426 (6600 950);
PAINT GREEN (6600 950);
DISPLAY INVISIBLE (6600 950);
FORCEADD PRELIM..10
(10260 2490);
PAINT GRAY (10260 2490);
FORCEPROP 2 LAST CDS_LIB mstr_misc
J 0
(10260 2490);
PAINT ORANGE (10260 2490);
DISPLAY INVISIBLE (10260 2490);
FORCEPROP 1 LAST COMMENT_BODY TRUE
J 0
(10260 2490);
PAINT ORANGE (10260 2490);
DISPLAY INVISIBLE (10260 2490);
FORCEADD BOM_NOTE..1
(6675 4450);
FORCEPROP 0 LAST L1 ASSEMBLY IPN PRIMARY :H63715-002,
J 0
(6525 4325);
DISPLAY 0.851064 (6525 4325);
PAINT WHITE (6525 4325);
FORCEPROP 2 LAST CDS_LIB mstr_symbols
J 0
(6675 4450);
PAINT ORANGE (6675 4450);
DISPLAY INVISIBLE (6675 4450);
FORCEPROP 2 LAST BOM_COST SB
J 0
(6525 4425);
DISPLAY 1.361702 (6525 4425);
PAINT ORANGE (6525 4425);
DISPLAY INVISIBLE (6525 4425);
FORCEPROP 1 LAST COMMENT_BODY TRUE
J 0
(6700 4550);
DISPLAY 1.319149 (6700 4550);
PAINT ORANGE (6700 4550);
DISPLAY INVISIBLE (6700 4550);
FORCEPROP 2 LAST ROOM SB_HEADERS
J 0
(6525 4425);
DISPLAY 1.361702 (6525 4425);
PAINT ORANGE (6525 4425);
DISPLAY INVISIBLE (6525 4425);
FORCEADD CAD_NOTE..1
(6900 2250);
FORCEPROP 0 LAST LINE2 WITHIN 1 OF CPU PINS
J 0
(6750 2050);
PAINT WHITE (6750 2050);
FORCEPROP 0 LAST LINE PLACE RCOMP RESISTORS
J 0
(6750 2125);
PAINT WHITE (6750 2125);
FORCEPROP 2 LAST CDS_LIB mstr_symbols
J 0
(6900 2250);
PAINT ORANGE (6900 2250);
DISPLAY INVISIBLE (6900 2250);
FORCEPROP 1 LAST COMMENT_BODY TRUE
J 0
(6925 2350);
DISPLAY 1.340426 (6925 2350);
PAINT GREEN (6925 2350);
DISPLAY INVISIBLE (6925 2350);
FORCEADD INTEL_CORP_BPAGE..1
(14300 -325);
FORCEPROP 1 LAST CDS_CON_LAST_MODIFIED Tue Dec 01 11:51:32 2015
J 0
(12875 0);
PAINT ORANGE (12875 0);
DISPLAY INVISIBLE (12875 0);
FORCEPROP 1 LAST CUSTOM_TXT_CDS <CURRENT_DESIGN_SHEET> OF <TOTAL_DESIGN_SHEETS>
J 0
(13800 -300);
PAINT GREEN (13800 -300);
FORCEPROP 1 LAST CUSTOM_TXT_CDS <CON_LAST_MODIFIED>
J 0
(12375 25);
PAINT GREEN (12375 25);
FORCEPROP 2 LAST CUSTOM_TXT_CDS <XR_PAGE_TITLE>
J 0
(6410 4925);
DISPLAY 0.638298 (6410 4925);
PAINT PINK (6410 4925);
DISPLAY INVISIBLE (6410 4925);
FORCEPROP 1 LAST SCH_ADDRESS3 Santa Clara, CA 95052-8119
J 0
(10325 -300);
DISPLAY 0.617021 (10325 -300);
PAINT GREEN (10325 -300);
FORCEPROP 1 LAST SCH_ADDRESS2 P.O. BOX 58119
J 0
(10325 -250);
DISPLAY 0.617021 (10325 -250);
PAINT GREEN (10325 -250);
FORCEPROP 1 LAST SCH_ADDRESS1 2200 Mission College Blvd.
J 0
(10325 -200);
DISPLAY 0.617021 (10325 -200);
PAINT GREEN (10325 -200);
FORCEPROP 1 LAST SCH_TITLE SKYLAKE - SKT1 - 1 OF 21
J 0
(6350 -275);
DISPLAY 1.212766 (6350 -275);
PAINT ORANGE (6350 -275);
FORCEPROP 1 LAST SCH_NUMBER H4694802
J 0
(13000 -175);
DISPLAY 1.212766 (13000 -175);
PAINT YELLOW (13000 -175);
FORCEPROP 1 LAST SCH_DEPT BESD
J 1
(9850 -225);
DISPLAY 1.212766 (9850 -225);
PAINT YELLOW (9850 -225);
FORCEPROP 1 LAST SCH_REV 2.420
J 0
(14050 -175);
DISPLAY 0.978723 (14050 -175);
PAINT YELLOW (14050 -175);
FORCEPROP 2 LAST PAGE_BORDER TRUE
J 0
(6410 4925);
DISPLAY 0.638298 (6410 4925);
PAINT PINK (6410 4925);
DISPLAY INVISIBLE (6410 4925);
FORCEPROP 2 LAST CDS_LIB mstr_symbols
J 0
(14300 -325);
PAINT MONO (14300 -325);
DISPLAY INVISIBLE (14300 -325);
FORCEPROP 1 LAST COMMENT_BODY TRUE
J 0
(14312 -313);
DISPLAY 0.468085 (14312 -313);
PAINT GREEN (14312 -313);
DISPLAY INVISIBLE (14312 -313);
FORCEPROP 2 LAST CDS_XR_PAGE_TITLE CR-55 : @BASEBOARD_FAB2_LIB.BASEBOARD_FAB2(SCH_1):PAGE55
J 0
(6410 4925);
DISPLAY 0.638298 (6410 4925);
PAINT PINK (6410 4925);
DISPLAY INVISIBLE (6410 4925);
WIRE 16 -1 (7700 2350)(7700 2425);
WIRE 16 -1 (7700 2350)(7475 2350);
WIRE 16 -1 (7475 2475)(7475 2350);
WIRE 16 -1 (7250 2350)(7475 2350);
WIRE 16 -1 (7250 2475)(7250 2350);
WIRE 16 -1 (7025 2350)(7250 2350);
WIRE 16 -1 (7025 2475)(7025 2350);
WIRE 16 -1 (6800 2350)(7025 2350);
WIRE 16 -1 (6800 2550)(6800 2350);
WIRE 16 -1 (6575 2350)(6800 2350);
WIRE 16 -1 (6575 2550)(6575 2350);
WIRE 16 -1 (6575 2350)(6575 2275);
WIRE 16 -1 (7400 1325)(7400 1225);
WIRE 16 -1 (7400 1225)(7200 1225);
WIRE 16 -1 (7200 1325)(7200 1225);
WIRE 16 -1 (7200 1225)(7000 1225);
WIRE 16 -1 (7000 1325)(7000 1225);
WIRE 16 -1 (7000 1225)(6775 1225);
WIRE 16 -1 (6775 1325)(6775 1225);
WIRE 16 -1 (6775 1225)(6575 1225);
WIRE 16 -1 (6575 1225)(6575 1325);
WIRE 16 -1 (6575 1075)(6575 1225);
WIRE 16 -1 (12875 2450)(12875 2575);
WIRE 16 -1 (12875 2575)(13075 2575);
WIRE 16 -1 (13075 2450)(13075 2575);
WIRE 16 -1 (13275 2575)(13075 2575);
WIRE 16 -1 (13275 2450)(13275 2575);
WIRE 16 -1 (13475 2575)(13275 2575);
WIRE 16 -1 (13475 2575)(13675 2575);
WIRE 16 -1 (13475 2575)(13475 2450);
WIRE 16 -1 (13675 2450)(13675 2575);
WIRE 16 -1 (13675 2650)(13675 2575);
WIRE 16 -1 (13275 1200)(13275 1275);
WIRE 16 -1 (13300 3125)(13300 2875);
WIRE 16 -1 (13300 2875)(13500 2875);
WIRE 16 -1 (13500 3125)(13500 2875);
WIRE 16 -1 (13500 2875)(13850 2875);
WIRE 16 -1 (13850 2875)(13850 2975);
WIRE 16 -1 (13575 4025)(13575 4175);
WIRE 16 -1 (13325 4175)(13575 4175);
WIRE 16 -1 (13325 4025)(13325 4175);
WIRE 16 -1 (13325 4175)(13325 4225);
WIRE 16 -1 (6575 2000)(9025 2000);
FORCEPROP 2 LAST SIG_NAME A_CPU1_PE3_RBIAS
J 0
(8050 2010);
DISPLAY 0.617021 (8050 2010);
PAINT ORANGE (8050 2010);
FORCEPROP 2 LASTPROP $XRERR UNIQUE?
J 0
(7810 2010);
DISPLAY 0.638298 (7810 2010);
PAINT MONO (7810 2010);
DISPLAY INVISIBLE (7810 2010);
WIRE 16 -1 (6575 2000)(6575 1525);
WIRE 16 -1 (9025 2000)(9275 2000);
WIRE 16 -1 (9025 1950)(9025 2000);
WIRE 16 -1 (9275 1950)(9025 1950);
WIRE 16 -1 (9275 1300)(8025 1300);
FORCEPROP 2 LAST SIG_NAME TP_XDP_CPU1_OBSDATA_B2_MBP4_N
J 0
(8040 1310);
DISPLAY 0.617021 (8040 1310);
PAINT ORANGE (8040 1310);
FORCEPROP 2 LASTPROP $XRERR UNIQUE?
J 0
(7785 1300);
DISPLAY 0.638298 (7785 1300);
PAINT MONO (7785 1300);
DISPLAY INVISIBLE (7785 1300);
WIRE 16 -1 (8025 1200)(9275 1200);
FORCEPROP 2 LAST SIG_NAME TP_XDP_CPU1_OBSDATA_B0_MBP2_N
J 0
(8040 1210);
DISPLAY 0.617021 (8040 1210);
PAINT ORANGE (8040 1210);
FORCEPROP 2 LASTPROP $XRERR UNIQUE?
J 0
(7785 1200);
DISPLAY 0.638298 (7785 1200);
PAINT MONO (7785 1200);
DISPLAY INVISIBLE (7785 1200);
WIRE 16 -1 (9275 1350)(8025 1350);
FORCEPROP 2 LAST SIG_NAME TP_XDP_CPU1_OBSDATA_B3_MBP5_N
J 0
(8040 1360);
DISPLAY 0.617021 (8040 1360);
PAINT ORANGE (8040 1360);
FORCEPROP 2 LASTPROP $XRERR UNIQUE?
J 0
(7785 1350);
DISPLAY 0.638298 (7785 1350);
PAINT MONO (7785 1350);
DISPLAY INVISIBLE (7785 1350);
WIRE 16 -1 (8025 1250)(9275 1250);
FORCEPROP 2 LAST SIG_NAME TP_XDP_CPU1_OBSDATA_B1_MBP3_N
J 0
(8040 1260);
DISPLAY 0.617021 (8040 1260);
PAINT ORANGE (8040 1260);
FORCEPROP 2 LASTPROP $XRERR UNIQUE?
J 0
(7785 1250);
DISPLAY 0.638298 (7785 1250);
PAINT MONO (7785 1250);
DISPLAY INVISIBLE (7785 1250);
WIRE 16 -1 (6575 2900)(9275 2900);
FORCEPROP 2 LAST SIG_NAME A_CPU1_GHJ_RCOMP2
J 0
(8050 2910);
DISPLAY 0.617021 (8050 2910);
PAINT ORANGE (8050 2910);
FORCEPROP 2 LASTPROP $XRERR UNIQUE?
J 0
(7810 2910);
DISPLAY 0.638298 (7810 2910);
PAINT MONO (7810 2910);
DISPLAY INVISIBLE (7810 2910);
WIRE 16 -1 (6575 2750)(6575 2900);
WIRE 16 -1 (9025 1750)(9275 1750);
WIRE 16 -1 (9025 1800)(9025 1750);
WIRE 16 -1 (9025 1800)(9275 1800);
WIRE 16 -1 (7000 1800)(9025 1800);
FORCEPROP 2 LAST SIG_NAME A_CPU1_UPI01_RBIAS
J 0
(8050 1810);
DISPLAY 0.617021 (8050 1810);
PAINT ORANGE (8050 1810);
FORCEPROP 2 LASTPROP $XRERR UNIQUE?
J 0
(7810 1810);
DISPLAY 0.638298 (7810 1810);
PAINT MONO (7810 1810);
DISPLAY INVISIBLE (7810 1810);
WIRE 16 -1 (7000 1525)(7000 1800);
WIRE 16 -1 (9275 2650)(7700 2650);
FORCEPROP 2 LAST SIG_NAME A_CPU1_KLM_RCOMP0
J 0
(8050 2660);
DISPLAY 0.617021 (8050 2660);
PAINT ORANGE (8050 2660);
FORCEPROP 2 LASTPROP $XRERR UNIQUE?
J 0
(7810 2660);
DISPLAY 0.638298 (7810 2660);
PAINT MONO (7810 2660);
DISPLAY INVISIBLE (7810 2660);
WIRE 16 -1 (7700 2625)(7700 2650);
WIRE 16 -1 (9275 2700)(7475 2700);
FORCEPROP 2 LAST SIG_NAME A_CPU1_KLM_RCOMP1
J 0
(8050 2710);
DISPLAY 0.617021 (8050 2710);
PAINT ORANGE (8050 2710);
FORCEPROP 2 LASTPROP $XRERR UNIQUE?
J 0
(7810 2710);
DISPLAY 0.638298 (7810 2710);
PAINT MONO (7810 2710);
DISPLAY INVISIBLE (7810 2710);
WIRE 16 -1 (7475 2675)(7475 2700);
WIRE 16 -1 (9275 2750)(7250 2750);
FORCEPROP 2 LAST SIG_NAME A_CPU1_KLM_RCOMP2
J 0
(8050 2760);
DISPLAY 0.617021 (8050 2760);
PAINT ORANGE (8050 2760);
FORCEPROP 2 LASTPROP $XRERR UNIQUE?
J 0
(7810 2760);
DISPLAY 0.638298 (7810 2760);
PAINT MONO (7810 2760);
DISPLAY INVISIBLE (7810 2760);
WIRE 16 -1 (7250 2675)(7250 2750);
WIRE 16 -1 (9275 2800)(7025 2800);
FORCEPROP 2 LAST SIG_NAME A_CPU1_GHJ_RCOMP0
J 0
(8050 2810);
DISPLAY 0.617021 (8050 2810);
PAINT ORANGE (8050 2810);
FORCEPROP 2 LASTPROP $XRERR UNIQUE?
J 0
(7810 2810);
DISPLAY 0.638298 (7810 2810);
PAINT MONO (7810 2810);
DISPLAY INVISIBLE (7810 2810);
WIRE 16 -1 (7025 2675)(7025 2800);
WIRE 16 -1 (9275 2850)(6800 2850);
FORCEPROP 2 LAST SIG_NAME A_CPU1_GHJ_RCOMP1
J 0
(8050 2860);
DISPLAY 0.617021 (8050 2860);
PAINT ORANGE (8050 2860);
FORCEPROP 2 LASTPROP $XRERR UNIQUE?
J 0
(7810 2860);
DISPLAY 0.638298 (7810 2860);
PAINT MONO (7810 2860);
DISPLAY INVISIBLE (7810 2860);
WIRE 16 -1 (6800 2750)(6800 2850);
WIRE 16 -1 (9275 1850)(9025 1850);
WIRE 16 -1 (9025 1850)(9025 1900);
WIRE 16 -1 (9275 1900)(9025 1900);
WIRE 16 -1 (9025 1900)(6775 1900);
FORCEPROP 2 LAST SIG_NAME A_CPU1_PE012_RBIAS
J 0
(8050 1910);
DISPLAY 0.617021 (8050 1910);
PAINT ORANGE (8050 1910);
FORCEPROP 2 LASTPROP $XRERR UNIQUE?
J 0
(7810 1910);
DISPLAY 0.638298 (7810 1910);
PAINT MONO (7810 1910);
DISPLAY INVISIBLE (7810 1910);
WIRE 16 -1 (6775 1900)(6775 1525);
WIRE 16 -1 (9025 1650)(9275 1650);
WIRE 16 -1 (9025 1700)(9025 1650);
WIRE 16 -1 (9025 1700)(9275 1700);
WIRE 16 -1 (7200 1700)(9025 1700);
FORCEPROP 2 LAST SIG_NAME A_CPU1_UPI2_RBIAS
J 0
(8050 1710);
DISPLAY 0.617021 (8050 1710);
PAINT ORANGE (8050 1710);
FORCEPROP 2 LASTPROP $XRERR UNIQUE?
J 0
(7810 1710);
DISPLAY 0.638298 (7810 1710);
PAINT MONO (7810 1710);
DISPLAY INVISIBLE (7810 1710);
WIRE 16 -1 (7200 1525)(7200 1700);
WIRE 16 -1 (9025 1550)(9275 1550);
WIRE 16 -1 (9025 1600)(9025 1550);
WIRE 16 -1 (9025 1600)(9275 1600);
WIRE 16 -1 (7400 1600)(9025 1600);
FORCEPROP 2 LAST SIG_NAME A_CPU1_MCP01_RBIAS
J 0
(8050 1610);
DISPLAY 0.617021 (8050 1610);
PAINT ORANGE (8050 1610);
FORCEPROP 2 LASTPROP $XRERR UNIQUE?
J 0
(7810 1610);
DISPLAY 0.638298 (7810 1610);
PAINT MONO (7810 1610);
DISPLAY INVISIBLE (7810 1610);
WIRE 16 -1 (7400 1525)(7400 1600);
WIRE 16 -1 (8025 1000)(9275 1000);
FORCEPROP 2 LAST SIG_NAME XDP_CPU1_TDI
J 0
(8050 1010);
DISPLAY 0.617021 (8050 1010);
PAINT ORANGE (8050 1010);
WIRE 16 -1 (8025 950)(9275 950);
FORCEPROP 2 LAST SIG_NAME XDP_CPU_TCK0
J 0
(8050 960);
DISPLAY 0.617021 (8050 960);
PAINT ORANGE (8050 960);
WIRE 16 -1 (9275 900)(8025 900);
FORCEPROP 2 LAST SIG_NAME XDP_CPU_TMS
J 0
(8050 910);
DISPLAY 0.617021 (8050 910);
PAINT ORANGE (8050 910);
WIRE 16 -1 (8025 850)(9275 850);
FORCEPROP 2 LAST SIG_NAME XDP_CPU_TRST_N
J 0
(8050 860);
DISPLAY 0.617021 (8050 860);
PAINT ORANGE (8050 860);
WIRE 16 -1 (9275 3800)(8025 3800);
FORCEPROP 2 LAST SIG_NAME CLK_100M_CPU1_BCLK2_DN
J 0
(8050 3810);
DISPLAY 0.617021 (8050 3810);
PAINT ORANGE (8050 3810);
WIRE 16 -1 (9275 3850)(8025 3850);
FORCEPROP 2 LAST SIG_NAME CLK_100M_CPU1_BCLK2_DP
J 0
(8050 3860);
DISPLAY 0.617021 (8050 3860);
PAINT ORANGE (8050 3860);
WIRE 16 -1 (9275 3050)(8000 3050);
FORCEPROP 2 LAST SIG_NAME M_H_CPU_VREF
J 0
(8025 3060);
DISPLAY 0.617021 (8025 3060);
PAINT ORANGE (8025 3060);
WIRE 16 -1 (9275 3100)(8000 3100);
FORCEPROP 2 LAST SIG_NAME M_J_CPU_VREF
J 0
(8025 3110);
DISPLAY 0.617021 (8025 3110);
PAINT ORANGE (8025 3110);
WIRE 16 -1 (9275 3200)(8000 3200);
FORCEPROP 2 LAST SIG_NAME M_L_CPU_VREF
J 0
(8025 3210);
DISPLAY 0.617021 (8025 3210);
PAINT ORANGE (8025 3210);
WIRE 16 -1 (9275 3250)(8000 3250);
FORCEPROP 2 LAST SIG_NAME M_M_CPU_VREF
J 0
(8025 3260);
DISPLAY 0.617021 (8025 3260);
PAINT ORANGE (8025 3260);
WIRE 16 -1 (8025 1450)(9275 1450);
FORCEPROP 2 LAST SIG_NAME XDP_CPU_OBSFN_B1_MBP7_N
J 0
(8050 1460);
DISPLAY 0.617021 (8050 1460);
PAINT ORANGE (8050 1460);
WIRE 16 -1 (9275 1400)(8025 1400);
FORCEPROP 2 LAST SIG_NAME XDP_CPU_OBSFN_B0_MBP6_N
J 0
(8050 1410);
DISPLAY 0.617021 (8050 1410);
PAINT ORANGE (8050 1410);
WIRE 16 -1 (9275 2150)(8050 2150);
FORCEPROP 2 LAST SIG_NAME SMB_PIROM_CPU1_SCL
J 0
(8075 2160);
DISPLAY 0.617021 (8075 2160);
PAINT ORANGE (8075 2160);
WIRE 16 -1 (9275 2100)(8050 2100);
FORCEPROP 2 LAST SIG_NAME SMB_PIROM_CPU1_SDA
J 0
(8075 2110);
DISPLAY 0.617021 (8075 2110);
PAINT ORANGE (8075 2110);
WIRE 16 -1 (8025 1150)(9275 1150);
FORCEPROP 2 LAST SIG_NAME XDP_CPU_MBP1_N
J 0
(8050 1160);
DISPLAY 0.617021 (8050 1160);
PAINT ORANGE (8050 1160);
WIRE 16 -1 (8025 1100)(9275 1100);
FORCEPROP 2 LAST SIG_NAME XDP_CPU_MBP0_N
J 0
(8050 1110);
DISPLAY 0.617021 (8050 1110);
PAINT ORANGE (8050 1110);
WIRE 16 -1 (9275 4150)(8025 4150);
FORCEPROP 2 LAST SIG_NAME CLK_100M_CPU1_BCLK0_DP
J 0
(8050 4160);
DISPLAY 0.617021 (8050 4160);
PAINT ORANGE (8050 4160);
WIRE 16 -1 (9275 4100)(8025 4100);
FORCEPROP 2 LAST SIG_NAME CLK_100M_CPU1_BCLK0_DN
J 0
(8050 4110);
DISPLAY 0.617021 (8050 4110);
PAINT ORANGE (8050 4110);
WIRE 16 -1 (9275 3950)(8025 3950);
FORCEPROP 2 LAST SIG_NAME CLK_100M_CPU1_BCLK1_DN
J 0
(8050 3960);
DISPLAY 0.617021 (8050 3960);
PAINT ORANGE (8050 3960);
WIRE 16 -1 (9275 4000)(8025 4000);
FORCEPROP 2 LAST SIG_NAME CLK_100M_CPU1_BCLK1_DP
J 0
(8050 4010);
DISPLAY 0.617021 (8050 4010);
PAINT ORANGE (8050 4010);
WIRE 16 -1 (9275 3700)(8025 3700);
FORCEPROP 2 LAST SIG_NAME PWRGD_CPU1_DRAMPWROK_GHJ_G
J 0
(8050 3710);
DISPLAY 0.617021 (8050 3710);
PAINT ORANGE (8050 3710);
WIRE 16 -1 (9275 3650)(8025 3650);
FORCEPROP 2 LAST SIG_NAME PWRGD_CPU1_DRAMPWROK_KLM_G
J 0
(8050 3660);
DISPLAY 0.617021 (8050 3660);
PAINT ORANGE (8050 3660);
WIRE 16 -1 (9275 3500)(8000 3500);
FORCEPROP 2 LAST SIG_NAME M_KLM_RST_N
J 0
(8025 3510);
DISPLAY 0.617021 (8025 3510);
PAINT ORANGE (8025 3510);
WIRE 16 -1 (9275 3550)(8000 3550);
FORCEPROP 2 LAST SIG_NAME M_GHJ_RST_N
J 0
(8025 3560);
DISPLAY 0.617021 (8025 3560);
PAINT ORANGE (8025 3560);
WIRE 16 -1 (9275 3400)(8025 3400);
FORCEPROP 2 LAST SIG_NAME H_CPU1_MEMGHJ_MEMHOT_G_N
J 0
(8050 3410);
DISPLAY 0.617021 (8050 3410);
PAINT ORANGE (8050 3410);
WIRE 16 -1 (8025 3350)(9275 3350);
FORCEPROP 2 LAST SIG_NAME H_CPU1_MEMKLM_MEMHOT_G_N
J 0
(8050 3360);
DISPLAY 0.617021 (8050 3360);
PAINT ORANGE (8050 3360);
WIRE 16 -1 (8000 3150)(9275 3150);
FORCEPROP 2 LAST SIG_NAME M_K_CPU_VREF
J 0
(8025 3160);
DISPLAY 0.617021 (8025 3160);
PAINT ORANGE (8025 3160);
WIRE 16 -1 (9275 3000)(8000 3000);
FORCEPROP 2 LAST SIG_NAME M_G_CPU_VREF
J 0
(8025 3010);
DISPLAY 0.617021 (8025 3010);
PAINT ORANGE (8025 3010);
WIRE 16 -1 (9275 2300)(8275 2300);
FORCEPROP 2 LAST SIG_NAME SMB_CPU1_PE_HP_GTL_SCL
J 0
(8300 2310);
DISPLAY 0.617021 (8300 2310);
PAINT ORANGE (8300 2310);
WIRE 16 -1 (8300 2250)(9275 2250);
FORCEPROP 2 LAST SIG_NAME SMB_CPU1_PE_HP_GTL_SDA
J 0
(8300 2260);
DISPLAY 0.617021 (8300 2260);
PAINT ORANGE (8300 2260);
WIRE 16 -1 (9275 2550)(8275 2550);
FORCEPROP 2 LAST SIG_NAME SMB_DDR_KLM_SDA_G_R
J 0
(8300 2560);
DISPLAY 0.617021 (8300 2560);
PAINT ORANGE (8300 2560);
WIRE 16 -1 (8275 2500)(9275 2500);
FORCEPROP 2 LAST SIG_NAME SMB_DDR_GHJ_SDA_G_R
J 0
(8300 2510);
DISPLAY 0.617021 (8300 2510);
PAINT ORANGE (8300 2510);
WIRE 16 -1 (9275 2450)(8275 2450);
FORCEPROP 2 LAST SIG_NAME SMB_DDR_KLM_SCL_G_R
J 0
(8300 2460);
DISPLAY 0.617021 (8300 2460);
PAINT ORANGE (8300 2460);
WIRE 16 -1 (8275 2400)(9275 2400);
FORCEPROP 2 LAST SIG_NAME SMB_DDR_GHJ_SCL_G_R
J 0
(8300 2410);
DISPLAY 0.617021 (8300 2410);
PAINT ORANGE (8300 2410);
WIRE 16 -1 (12125 625)(12125 200);
WIRE 16 -1 (12200 3450)(11175 3450);
FORCEPROP 2 LAST SIG_NAME SVID_CLK0_CPU1
J 0
(11325 3460);
DISPLAY 0.617021 (11325 3460);
PAINT ORANGE (11325 3460);
FORCEPROP 2 LASTPROP $XRERR UNIQUE?
J 0
(11085 3460);
DISPLAY 0.638298 (11085 3460);
PAINT MONO (11085 3460);
DISPLAY INVISIBLE (11085 3460);
WIRE 16 -1 (12200 3600)(11175 3600);
FORCEPROP 2 LAST SIG_NAME SVID_CLK1_CPU1
J 0
(11325 3610);
DISPLAY 0.617021 (11325 3610);
PAINT ORANGE (11325 3610);
FORCEPROP 2 LASTPROP $XRERR UNIQUE?
J 0
(11085 3610);
DISPLAY 0.638298 (11085 3610);
PAINT MONO (11085 3610);
DISPLAY INVISIBLE (11085 3610);
WIRE 16 -1 (12200 3550)(11175 3550);
FORCEPROP 2 LAST SIG_NAME SVID_ALERT1_CPU1_N
J 0
(11325 3560);
DISPLAY 0.617021 (11325 3560);
PAINT ORANGE (11325 3560);
FORCEPROP 2 LASTPROP $XRERR UNIQUE?
J 0
(11085 3560);
DISPLAY 0.638298 (11085 3560);
PAINT MONO (11085 3560);
DISPLAY INVISIBLE (11085 3560);
WIRE 16 -1 (11700 3900)(11175 3900);
FORCEPROP 2 LAST SIG_NAME H_PM_SYNC_GTL_R2
J 0
(11300 3910);
DISPLAY 0.617021 (11300 3910);
PAINT ORANGE (11300 3910);
FORCEPROP 2 LASTPROP $XRERR UNIQUE?
J 0
(11060 3910);
DISPLAY 0.638298 (11060 3910);
PAINT MONO (11060 3910);
DISPLAY INVISIBLE (11060 3910);
WIRE 16 -1 (12200 3500)(11175 3500);
FORCEPROP 2 LAST SIG_NAME SVID_DIO0_CPU1
J 0
(11325 3510);
DISPLAY 0.617021 (11325 3510);
PAINT ORANGE (11325 3510);
FORCEPROP 2 LASTPROP $XRERR UNIQUE?
J 0
(11085 3510);
DISPLAY 0.638298 (11085 3510);
PAINT MONO (11085 3510);
DISPLAY INVISIBLE (11085 3510);
WIRE 16 -1 (12200 3400)(11175 3400);
FORCEPROP 2 LAST SIG_NAME SVID_ALERT0_CPU1_N
J 0
(11325 3410);
DISPLAY 0.617021 (11325 3410);
PAINT ORANGE (11325 3410);
FORCEPROP 2 LASTPROP $XRERR UNIQUE?
J 0
(11085 3410);
DISPLAY 0.638298 (11085 3410);
PAINT MONO (11085 3410);
DISPLAY INVISIBLE (11085 3410);
WIRE 16 -1 (11825 3850)(11175 3850);
FORCEPROP 0 LAST SIG_NAME H_PMSYNC_CLK_24M_CPU1
J 0
(11315 3860);
DISPLAY 0.617021 (11315 3860);
PAINT ORANGE (11315 3860);
FORCEPROP 2 LASTPROP $XRERR UNIQUE?
J 0
(11075 3860);
DISPLAY 0.638298 (11075 3860);
PAINT MONO (11075 3860);
DISPLAY INVISIBLE (11075 3860);
WIRE 16 -1 (12200 3650)(11175 3650);
FORCEPROP 2 LAST SIG_NAME SVID_DIO1_CPU1
J 0
(11325 3660);
DISPLAY 0.617021 (11325 3660);
PAINT ORANGE (11325 3660);
FORCEPROP 2 LASTPROP $XRERR UNIQUE?
J 0
(11085 3660);
DISPLAY 0.638298 (11085 3660);
PAINT MONO (11085 3660);
DISPLAY INVISIBLE (11085 3660);
WIRE 16 -1 (11175 2200)(12475 2200);
FORCEPROP 2 LAST SIG_NAME TP_CPU1_SOCKET_ID_2
J 0
(11425 2210);
DISPLAY 0.617021 (11425 2210);
PAINT ORANGE (11425 2210);
FORCEPROP 2 LASTPROP $XRERR UNIQUE?
J 0
(12505 2200);
DISPLAY 0.638298 (12505 2200);
PAINT MONO (12505 2200);
DISPLAY INVISIBLE (12505 2200);
WIRE 16 -1 (12475 2900)(11175 2900);
FORCEPROP 2 LAST SIG_NAME TP_CPU1_PROC_DIS_G_N
J 0
(11425 2910);
DISPLAY 0.617021 (11425 2910);
PAINT ORANGE (11425 2910);
FORCEPROP 2 LASTPROP $XRERR UNIQUE?
J 0
(12505 2900);
DISPLAY 0.638298 (12505 2900);
PAINT MONO (12505 2900);
DISPLAY INVISIBLE (12505 2900);
WIRE 16 -1 (11725 250)(13875 250);
WIRE 16 -1 (11725 325)(13850 325);
WIRE 16 -1 (11725 450)(13875 450);
WIRE 16 -1 (12475 1600)(11175 1600);
FORCEPROP 2 LAST SIG_NAME TP_CPU1_NMI
J 0
(11425 1610);
DISPLAY 0.617021 (11425 1610);
PAINT ORANGE (11425 1610);
FORCEPROP 2 LASTPROP $XRERR UNIQUE?
J 0
(12505 1600);
DISPLAY 0.638298 (12505 1600);
PAINT MONO (12505 1600);
DISPLAY INVISIBLE (12505 1600);
WIRE 16 -1 (11725 525)(13875 525);
WIRE 16 -1 (11675 175)(13925 175);
WIRE 16 -1 (11675 650)(11675 175);
WIRE 16 -1 (13925 175)(13925 650);
WIRE 16 -1 (11675 650)(13925 650);
WIRE 16 -1 (12475 4100)(11175 4100);
FORCEPROP 2 LAST SIG_NAME RST_CPU1_G_N
J 0
(11425 4110);
DISPLAY 0.617021 (11425 4110);
PAINT ORANGE (11425 4110);
WIRE 16 -1 (12475 3900)(11900 3900);
FORCEPROP 2 LAST SIG_NAME H_PM_SYNC_GTL
J 0
(12040 3910);
DISPLAY 0.617021 (12040 3910);
PAINT ORANGE (12040 3910);
WIRE 16 -1 (12475 4000)(11175 4000);
FORCEPROP 2 LAST SIG_NAME PU_CPU1_EAR_N
J 0
(11425 4010);
DISPLAY 0.617021 (11425 4010);
PAINT ORANGE (11425 4010);
WIRE 16 -1 (12475 3850)(12025 3850);
FORCEPROP 2 LAST SIG_NAME H_PMSYNC_CLK_24M
J 0
(12040 3860);
DISPLAY 0.617021 (12040 3860);
PAINT ORANGE (12040 3860);
WIRE 16 -1 (11175 2300)(12475 2300);
FORCEPROP 2 LAST SIG_NAME PU_CPU1_SOCKET_ID_1
J 0
(11425 2310);
DISPLAY 0.617021 (11425 2310);
PAINT ORANGE (11425 2310);
WIRE 16 -1 (11175 2250)(12475 2250);
FORCEPROP 2 LAST SIG_NAME PU_CPU1_SOCKET_ID_0
J 0
(11425 2260);
DISPLAY 0.617021 (11425 2260);
PAINT ORANGE (11425 2260);
WIRE 16 -1 (12475 1750)(11175 1750);
FORCEPROP 2 LAST SIG_NAME PU_CPU1_TSC_SYNC
J 0
(11438 1772);
DISPLAY 0.617021 (11438 1772);
PAINT ORANGE (11438 1772);
WIRE 16 -1 (12475 1550)(11175 1550);
FORCEPROP 2 LAST SIG_NAME PU_CPU1_LEGACY_SKT
J 0
(11425 1560);
DISPLAY 0.617021 (11425 1560);
PAINT ORANGE (11425 1560);
WIRE 16 -1 (12475 1300)(11175 1300);
FORCEPROP 2 LAST SIG_NAME PD_CPU1_KSFC_DIS
J 0
(11427 1306);
DISPLAY 0.617021 (11427 1306);
PAINT ORANGE (11427 1306);
WIRE 16 -1 (12475 1250)(11175 1250);
FORCEPROP 2 LAST SIG_NAME PD_CPU1_TEST14
J 0
(11425 1260);
DISPLAY 0.617021 (11425 1260);
PAINT ORANGE (11425 1260);
WIRE 16 -1 (12475 1200)(11175 1200);
FORCEPROP 2 LAST SIG_NAME PD_CPU1_TEST13
J 0
(11425 1210);
DISPLAY 0.617021 (11425 1210);
PAINT ORANGE (11425 1210);
WIRE 16 -1 (12475 1150)(11175 1150);
FORCEPROP 2 LAST SIG_NAME PD_CPU1_TEST12
J 0
(11425 1160);
DISPLAY 0.617021 (11425 1160);
PAINT ORANGE (11425 1160);
WIRE 16 -1 (12500 1050)(11175 1050);
FORCEPROP 2 LAST SIG_NAME XDP_CPU_PREQ_N
J 0
(11425 1060);
DISPLAY 0.617021 (11425 1060);
PAINT ORANGE (11425 1060);
WIRE 16 -1 (12500 1000)(11175 1000);
FORCEPROP 2 LAST SIG_NAME XDP_CPU_PRDY_N
J 0
(11425 1010);
DISPLAY 0.617021 (11425 1010);
PAINT ORANGE (11425 1010);
WIRE 16 -1 (12475 1700)(11175 1700);
FORCEPROP 2 LAST SIG_NAME FM_CPU1_SM_WP
J 0
(11425 1710);
DISPLAY 0.617021 (11425 1710);
PAINT ORANGE (11425 1710);
WIRE 16 -1 (12475 1450)(11175 1450);
FORCEPROP 2 LAST SIG_NAME PD_PIROM_CPU1_ADDR2
J 0
(11425 1460);
DISPLAY 0.617021 (11425 1460);
PAINT ORANGE (11425 1460);
WIRE 16 -1 (12475 1400)(11175 1400);
FORCEPROP 2 LAST SIG_NAME PD_PIROM_CPU1_ADDR1
J 0
(11425 1410);
DISPLAY 0.617021 (11425 1410);
PAINT ORANGE (11425 1410);
WIRE 16 -1 (12475 1350)(11175 1350);
FORCEPROP 2 LAST SIG_NAME PU_PIROM_CPU1_ADDR0
J 0
(11425 1360);
DISPLAY 0.617021 (11425 1360);
PAINT ORANGE (11425 1360);
WIRE 16 -1 (12475 3750)(11175 3750);
FORCEPROP 2 LAST SIG_NAME PECI_CPU_G
J 0
(11425 3760);
DISPLAY 0.617021 (11425 3760);
PAINT ORANGE (11425 3760);
WIRE 16 -1 (12450 3300)(11175 3300);
FORCEPROP 2 LAST SIG_NAME H_CPU1_CATERR_G_N
J 0
(11425 3310);
DISPLAY 0.617021 (11425 3310);
PAINT ORANGE (11425 3310);
WIRE 16 -1 (12475 3200)(11175 3200);
FORCEPROP 2 LAST SIG_NAME H_CPU1_ERR2_G_N
J 0
(11425 3210);
DISPLAY 0.617021 (11425 3210);
PAINT ORANGE (11425 3210);
WIRE 16 -1 (12450 3000)(11175 3000);
FORCEPROP 2 LAST SIG_NAME H_CPU1_MSMI_G_N
J 0
(11425 3010);
DISPLAY 0.617021 (11425 3010);
PAINT ORANGE (11425 3010);
WIRE 16 -1 (12475 3100)(11175 3100);
FORCEPROP 2 LAST SIG_NAME H_CPU1_ERR0_G_N
J 0
(11425 3110);
DISPLAY 0.617021 (11425 3110);
PAINT ORANGE (11425 3110);
WIRE 16 -1 (12475 3150)(11175 3150);
FORCEPROP 2 LAST SIG_NAME H_CPU1_ERR1_G_N
J 0
(11425 3160);
DISPLAY 0.617021 (11425 3160);
PAINT ORANGE (11425 3160);
WIRE 16 -1 (12450 2850)(11175 2850);
FORCEPROP 2 LAST SIG_NAME H_CPU1_PROCHOT_G_N
J 0
(11425 2860);
DISPLAY 0.617021 (11425 2860);
PAINT ORANGE (11425 2860);
WIRE 16 -1 (12475 2800)(11175 2800);
FORCEPROP 2 LAST SIG_NAME H_CPU1_THERMTRIP_G_N
J 0
(11425 2810);
DISPLAY 0.617021 (11425 2810);
PAINT ORANGE (11425 2810);
WIRE 16 -1 (12475 2700)(11175 2700);
FORCEPROP 2 LAST SIG_NAME PU_CPU1_SAFE_MODE_BOOT
J 0
(11425 2710);
DISPLAY 0.617021 (11425 2710);
PAINT ORANGE (11425 2710);
WIRE 16 -1 (12475 2600)(11175 2600);
FORCEPROP 2 LAST SIG_NAME H_CPU1_BMCINIT
J 0
(11425 2610);
DISPLAY 0.617021 (11425 2610);
PAINT ORANGE (11425 2610);
WIRE 16 -1 (12475 2650)(11175 2650);
FORCEPROP 2 LAST SIG_NAME PU_CPU1_FRMAGENT
J 0
(11425 2660);
DISPLAY 0.617021 (11425 2660);
PAINT ORANGE (11425 2660);
WIRE 16 -1 (12475 2500)(11175 2500);
FORCEPROP 2 LAST SIG_NAME PD_CPU1_TXT_PLTEN
J 0
(11425 2510);
DISPLAY 0.617021 (11425 2510);
PAINT ORANGE (11425 2510);
WIRE 16 -1 (12475 2550)(11175 2550);
FORCEPROP 2 LAST SIG_NAME PU_CPU1_TXT_AGENT
J 0
(11425 2560);
DISPLAY 0.617021 (11425 2560);
PAINT ORANGE (11425 2560);
WIRE 16 -1 (12450 2400)(11175 2400);
FORCEPROP 2 LAST SIG_NAME H_CPU1_FAST_WAKE_N
J 0
(11425 2410);
DISPLAY 0.617021 (11425 2410);
PAINT ORANGE (11425 2410);
WIRE 16 -1 (12475 2450)(11175 2450);
FORCEPROP 2 LAST SIG_NAME PD_CPU1_BIST_ENABLE
J 0
(11425 2460);
DISPLAY 0.617021 (11425 2460);
PAINT ORANGE (11425 2460);
WIRE 16 -1 (12525 800)(11175 800);
FORCEPROP 2 LAST SIG_NAME XDP_CPU1_TDO
J 0
(11425 810);
DISPLAY 0.617021 (11425 810);
PAINT ORANGE (11425 810);
WIRE 16 -1 (12475 4150)(11175 4150);
FORCEPROP 2 LAST SIG_NAME PWRGD_CPU1_G
J 0
(11425 4160);
DISPLAY 0.617021 (11425 4160);
PAINT ORANGE (11425 4160);
WIRE 16 -1 (12900 625)(12900 200);
WIRE 16 -1 (13275 1000)(13275 900);
WIRE 16 -1 (13275 900)(13525 900);
WIRE 16 -1 (11175 900)(13275 900);
FORCEPROP 2 LAST SIG_NAME FM_CPU1_SKTOCC_LVT3_N
J 0
(11425 910);
DISPLAY 0.617021 (11425 910);
PAINT ORANGE (11425 910);
WIRE 16 -1 (13350 625)(13350 200);
WIRE 16 -1 (13475 2250)(13475 1900);
WIRE 16 -1 (13750 1900)(13475 1900);
WIRE 16 -1 (13475 1900)(11175 1900);
FORCEPROP 2 LAST SIG_NAME FM_CPU1_PKGID1
J 0
(11425 1910);
DISPLAY 0.617021 (11425 1910);
PAINT ORANGE (11425 1910);
WIRE 16 -1 (13275 2250)(13275 1950);
WIRE 16 -1 (13750 1950)(13275 1950);
WIRE 16 -1 (13275 1950)(11175 1950);
FORCEPROP 2 LAST SIG_NAME FM_CPU1_PKGID2
J 0
(11425 1960);
DISPLAY 0.617021 (11425 1960);
PAINT ORANGE (11425 1960);
WIRE 16 -1 (13675 2250)(13675 1850);
WIRE 16 -1 (13750 1850)(13675 1850);
WIRE 16 -1 (13675 1850)(11175 1850);
FORCEPROP 2 LAST SIG_NAME FM_CPU1_PKGID0
J 0
(11425 1860);
DISPLAY 0.617021 (11425 1860);
PAINT ORANGE (11425 1860);
WIRE 16 -1 (12400 3600)(13700 3600);
FORCEPROP 2 LAST SIG_NAME SVID_CLK1_CPU1_R
J 0
(12750 3610);
DISPLAY 0.617021 (12750 3610);
PAINT ORANGE (12750 3610);
WIRE 16 -1 (12400 3450)(13700 3450);
FORCEPROP 2 LAST SIG_NAME SVID_CLK0_CPU1_R
J 0
(12750 3460);
DISPLAY 0.617021 (12750 3460);
PAINT ORANGE (12750 3460);
WIRE 16 -1 (12875 2250)(12875 2100);
WIRE 16 -1 (12875 2100)(13750 2100);
WIRE 16 -1 (11175 2100)(12875 2100);
FORCEPROP 2 LAST SIG_NAME FM_CPU1_PROC_ID1
J 0
(11425 2110);
DISPLAY 0.617021 (11425 2110);
PAINT ORANGE (11425 2110);
WIRE 16 -1 (13075 2250)(13075 2050);
WIRE 16 -1 (13075 2050)(13750 2050);
WIRE 16 -1 (11175 2050)(13075 2050);
FORCEPROP 2 LAST SIG_NAME FM_CPU1_PROC_ID0
J 0
(11425 2060);
DISPLAY 0.617021 (11425 2060);
PAINT ORANGE (11425 2060);
WIRE 16 -1 (13675 3500)(13300 3500);
WIRE 16 -1 (13300 3325)(13300 3500);
WIRE 16 -1 (13300 3500)(12400 3500);
FORCEPROP 2 LAST SIG_NAME SVID_DIO0_CPU1_R
J 0
(12750 3510);
DISPLAY 0.617021 (12750 3510);
PAINT ORANGE (12750 3510);
WIRE 16 -1 (13500 3325)(13500 3400);
WIRE 16 -1 (13700 3400)(13500 3400);
WIRE 16 -1 (12400 3400)(13500 3400);
FORCEPROP 2 LAST SIG_NAME SVID_ALERT0_CPU1_R_N
J 0
(12750 3410);
DISPLAY 0.617021 (12750 3410);
PAINT ORANGE (12750 3410);
WIRE 16 -1 (13700 3550)(13575 3550);
WIRE 16 -1 (13575 3825)(13575 3550);
WIRE 16 -1 (12400 3550)(13575 3550);
FORCEPROP 2 LAST SIG_NAME SVID_ALERT1_CPU1_R_N
J 0
(12750 3560);
DISPLAY 0.617021 (12750 3560);
PAINT ORANGE (12750 3560);
WIRE 16 -1 (13675 3650)(13325 3650);
WIRE 16 -1 (13325 3825)(13325 3650);
WIRE 16 -1 (13325 3650)(12400 3650);
FORCEPROP 2 LAST SIG_NAME SVID_DIO1_CPU1_R
J 0
(12750 3660);
DISPLAY 0.617021 (12750 3660);
PAINT ORANGE (12750 3660);
DOT 1 (13075 2575);
DOT 1 (13275 2575);
DOT 1 (13475 2575);
DOT 1 (13275 900);
DOT 1 (7025 2350);
DOT 1 (7200 1225);
DOT 1 (9025 1700);
DOT 1 (6575 2350);
DOT 1 (13675 1850);
DOT 1 (13475 1900);
DOT 1 (13075 2050);
DOT 1 (13675 2575);
DOT 1 (13300 3500);
DOT 1 (7475 2350);
DOT 1 (7250 2350);
DOT 1 (13575 3550);
DOT 1 (9025 2000);
DOT 1 (9025 1900);
DOT 1 (9025 1800);
DOT 1 (6575 1225);
DOT 1 (6775 1225);
DOT 1 (7000 1225);
DOT 1 (9025 1600);
DOT 1 (13275 1950);
DOT 1 (13500 2875);
DOT 1 (13325 4175);
DOT 1 (6800 2350);
DOT 1 (13325 3650);
DOT 1 (12875 2100);
DOT 1 (13500 3400);
FORCENOTE
ALTERNATE: H63715-002
(6525 4275) 0;
DISPLAY LEFT (6525 4275);
DISPLAY 0.808511 (6525 4275);
PAINT PURPLE (6525 4275);
FORCENOTE
PROC_ID [1:0]
(11725 575) 0;
DISPLAY LEFT (11725 575);
DISPLAY 0.808511 (11725 575);
PAINT PURPLE (11725 575);
FORCENOTE
2'B01
(11825 375) 0;
DISPLAY LEFT (11825 375);
DISPLAY 0.638298 (11825 375);
PAINT PURPLE (11825 375);
FORCENOTE
2'B10
(11825 275) 0;
DISPLAY LEFT (11825 275);
DISPLAY 0.638298 (11825 275);
PAINT PURPLE (11825 275);
FORCENOTE
2'B00
(11825 475) 0;
DISPLAY LEFT (11825 475);
DISPLAY 0.638298 (11825 475);
PAINT PURPLE (11825 475);
FORCENOTE
2'B11
(11825 200) 0;
DISPLAY LEFT (11825 200);
DISPLAY 0.638298 (11825 200);
PAINT PURPLE (11825 200);
FORCENOTE
RESERVED
(12150 275) 0;
DISPLAY LEFT (12150 275);
DISPLAY 0.638298 (12150 275);
PAINT PURPLE (12150 275);
FORCENOTE
RESERVED
(12150 200) 0;
DISPLAY LEFT (12150 200);
DISPLAY 0.638298 (12150 200);
PAINT PURPLE (12150 200);
FORCENOTE
SKYLAKE PROCESSOR 
(12150 475) 0;
DISPLAY LEFT (12150 475);
DISPLAY 0.638298 (12150 475);
PAINT PURPLE (12150 475);
FORCENOTE
RESERVED FOR FUTURE PROCESSOR
(12150 375) 0;
DISPLAY LEFT (12150 375);
DISPLAY 0.638298 (12150 375);
PAINT PURPLE (12150 375);
FORCENOTE
DEFINITION
(12325 575) 0;
DISPLAY LEFT (12325 575);
DISPLAY 0.808511 (12325 575);
PAINT PURPLE (12325 575);
FORCENOTE
3'B001
(12950 375) 0;
DISPLAY LEFT (12950 375);
DISPLAY 0.638298 (12950 375);
PAINT PURPLE (12950 375);
FORCENOTE
3'B010
(12950 275) 0;
DISPLAY LEFT (12950 275);
DISPLAY 0.638298 (12950 275);
PAINT PURPLE (12950 275);
FORCENOTE
3'B000
(12950 475) 0;
DISPLAY LEFT (12950 475);
DISPLAY 0.638298 (12950 475);
PAINT PURPLE (12950 475);
FORCENOTE
3'B111-3'B011
(12950 200) 0;
DISPLAY LEFT (12950 200);
DISPLAY 0.638298 (12950 200);
PAINT PURPLE (12950 200);
FORCENOTE
PKG_ID[2:0]
(12925 575) 0;
DISPLAY LEFT (12925 575);
DISPLAY 0.808511 (12925 575);
PAINT PURPLE (12925 575);
FORCENOTE
RESERVED
(13400 275) 0;
DISPLAY LEFT (13400 275);
DISPLAY 0.638298 (13400 275);
PAINT PURPLE (13400 275);
FORCENOTE
RESERVED
(13400 200) 0;
DISPLAY LEFT (13400 200);
DISPLAY 0.638298 (13400 200);
PAINT PURPLE (13400 200);
FORCENOTE
MCP SUPPORT
(13375 350) 0;
DISPLAY LEFT (13375 350);
DISPLAY 0.638298 (13375 350);
PAINT PURPLE (13375 350);
FORCENOTE
NON-MCP SUPPORT
(13375 475) 0;
DISPLAY LEFT (13375 475);
DISPLAY 0.638298 (13375 475);
PAINT PURPLE (13375 475);
FORCENOTE
DEFINITION
(13500 575) 0;
DISPLAY LEFT (13500 575);
DISPLAY 0.808511 (13500 575);
PAINT PURPLE (13500 575);
FORCENOTE
HOST FABRIC INTERFACE
(13375 400) 0;
DISPLAY LEFT (13375 400);
DISPLAY 0.638298 (13375 400);
PAINT PURPLE (13375 400);
FORCENOTE
PIROM_ADDR[2:0] 3B001
(13092 1492) 0;
DISPLAY LEFT (13092 1492);
DISPLAY 1.021277 (13092 1492);
PAINT PURPLE (13092 1492);
QUIT
